FILE_TYPE = MACRO_DRAWING;
SET COLOR_WIRE YELLOW;
SET COLOR_PROP ORANGE;
SET COLOR_DOT WHITE;
SET COLOR_ARC YELLOW;
SET COLOR_BODY GREEN;
SET COLOR_NOTE PURPLE;
SET PROP_DISPLAY VALUE;
SET PAGE_NUMBER P37;
FORCEADD GENOA_SP5..1
(-4575 3675);
FORCEPROP 1 LAST LOCATION U26
J 0
(-5220 6481);
DISPLAY 0.489362 (-5220 6481);
PAINT SKYBLUE (-5220 6481);
FORCEPROP 0 LAST $SEC 1
J 0
(-5200 6525);
DISPLAY 0.680851 (-5200 6525);
PAINT MONO (-5200 6525);
DISPLAY INVISIBLE (-5200 6525);
FORCEPROP 0 LAST CDS_SEC 1
J 0
(-5225 6425);
DISPLAY 1.021277 (-5225 6425);
DISPLAY INVISIBLE (-5225 6425);
FORCEPROP 0 LASTPIN (-5375 3075) $PN BC74
J 2
(-5385 3085);
DISPLAY 0.489362 (-5385 3085);
PAINT MONO (-5385 3085);
FORCEPROP 0 LASTPIN (-5375 3025) $PN BD74
J 2
(-5385 3035);
DISPLAY 0.489362 (-5385 3035);
PAINT MONO (-5385 3035);
FORCEPROP 0 LASTPIN (-5375 1925) $PN BF74
J 2
(-5385 1935);
DISPLAY 0.489362 (-5385 1935);
PAINT MONO (-5385 1935);
FORCEPROP 0 LASTPIN (-5375 1875) $PN BG74
J 2
(-5385 1885);
DISPLAY 0.489362 (-5385 1885);
PAINT MONO (-5385 1885);
FORCEPROP 0 LASTPIN (-5375 2225) $PN AR74
J 2
(-5385 2235);
DISPLAY 0.489362 (-5385 2235);
PAINT MONO (-5385 2235);
FORCEPROP 0 LASTPIN (-5375 2125) $PN AT74
J 2
(-5385 2135);
DISPLAY 0.489362 (-5385 2135);
PAINT MONO (-5385 2135);
FORCEPROP 0 LASTPIN (-5375 2925) $PN AV74
J 2
(-5385 2935);
DISPLAY 0.489362 (-5385 2935);
PAINT MONO (-5385 2935);
FORCEPROP 0 LASTPIN (-5375 2875) $PN AW73
J 2
(-5385 2885);
DISPLAY 0.489362 (-5385 2885);
PAINT MONO (-5385 2885);
FORCEPROP 0 LASTPIN (-5375 2775) $PN BN73
J 2
(-5385 2785);
DISPLAY 0.489362 (-5385 2785);
PAINT MONO (-5385 2785);
FORCEPROP 0 LASTPIN (-5375 1775) $PN AU74
J 2
(-5385 1785);
DISPLAY 0.489362 (-5385 1785);
PAINT MONO (-5385 1785);
FORCEPROP 0 LASTPIN (-5375 1725) $PN AV72
J 2
(-5385 1735);
DISPLAY 0.489362 (-5385 1735);
PAINT MONO (-5385 1735);
FORCEPROP 0 LASTPIN (-5375 1625) $PN BP72
J 2
(-5385 1635);
DISPLAY 0.489362 (-5385 1635);
PAINT MONO (-5385 1635);
FORCEPROP 0 LASTPIN (-5375 3925) $PN AW74
J 2
(-5385 3935);
DISPLAY 0.489362 (-5385 3935);
PAINT MONO (-5385 3935);
FORCEPROP 0 LASTPIN (-5375 3875) $PN AY74
J 2
(-5385 3885);
DISPLAY 0.489362 (-5385 3885);
PAINT MONO (-5385 3885);
FORCEPROP 0 LASTPIN (-5375 3825) $PN AY72
J 2
(-5385 3835);
DISPLAY 0.489362 (-5385 3835);
PAINT MONO (-5385 3835);
FORCEPROP 0 LASTPIN (-5375 3775) $PN BA73
J 2
(-5385 3785);
DISPLAY 0.489362 (-5385 3785);
PAINT MONO (-5385 3785);
FORCEPROP 0 LASTPIN (-5375 3725) $PN BA74
J 2
(-5385 3735);
DISPLAY 0.489362 (-5385 3735);
PAINT MONO (-5385 3735);
FORCEPROP 0 LASTPIN (-5375 3675) $PN BB74
J 2
(-5385 3685);
DISPLAY 0.489362 (-5385 3685);
PAINT MONO (-5385 3685);
FORCEPROP 0 LASTPIN (-5375 3625) $PN BB72
J 2
(-5385 3635);
DISPLAY 0.489362 (-5385 3635);
PAINT MONO (-5385 3635);
FORCEPROP 0 LASTPIN (-3775 2475) $PN AJ74
J 0
(-3765 2485);
DISPLAY 0.489362 (-3765 2485);
PAINT MONO (-3765 2485);
FORCEPROP 0 LASTPIN (-3775 2425) $PN AK72
J 0
(-3765 2435);
DISPLAY 0.489362 (-3765 2435);
PAINT MONO (-3765 2435);
FORCEPROP 0 LASTPIN (-3775 2375) $PN AK74
J 0
(-3765 2385);
DISPLAY 0.489362 (-3765 2385);
PAINT MONO (-3765 2385);
FORCEPROP 0 LASTPIN (-3775 2325) $PN AL73
J 0
(-3765 2335);
DISPLAY 0.489362 (-3765 2335);
PAINT MONO (-3765 2335);
FORCEPROP 0 LASTPIN (-3775 2275) $PN AN74
J 0
(-3765 2285);
DISPLAY 0.489362 (-3765 2285);
PAINT MONO (-3765 2285);
FORCEPROP 0 LASTPIN (-3775 2225) $PN AP72
J 0
(-3765 2235);
DISPLAY 0.489362 (-3765 2235);
PAINT MONO (-3765 2235);
FORCEPROP 0 LASTPIN (-3775 2175) $PN AP74
J 0
(-3765 2185);
DISPLAY 0.489362 (-3765 2185);
PAINT MONO (-3765 2185);
FORCEPROP 0 LASTPIN (-3775 2125) $PN AR73
J 0
(-3765 2135);
DISPLAY 0.489362 (-3765 2135);
PAINT MONO (-3765 2135);
FORCEPROP 0 LASTPIN (-3775 6075) $PN E74
J 0
(-3765 6085);
DISPLAY 0.489362 (-3765 6085);
PAINT MONO (-3765 6085);
FORCEPROP 0 LASTPIN (-3775 6025) $PN F72
J 0
(-3765 6035);
DISPLAY 0.489362 (-3765 6035);
PAINT MONO (-3765 6035);
FORCEPROP 0 LASTPIN (-3775 5975) $PN F74
J 0
(-3765 5985);
DISPLAY 0.489362 (-3765 5985);
PAINT MONO (-3765 5985);
FORCEPROP 0 LASTPIN (-3775 5925) $PN G73
J 0
(-3765 5935);
DISPLAY 0.489362 (-3765 5935);
PAINT MONO (-3765 5935);
FORCEPROP 0 LASTPIN (-3775 5875) $PN J74
J 0
(-3765 5885);
DISPLAY 0.489362 (-3765 5885);
PAINT MONO (-3765 5885);
FORCEPROP 0 LASTPIN (-3775 5825) $PN K72
J 0
(-3765 5835);
DISPLAY 0.489362 (-3765 5835);
PAINT MONO (-3765 5835);
FORCEPROP 0 LASTPIN (-3775 5775) $PN K74
J 0
(-3765 5785);
DISPLAY 0.489362 (-3765 5785);
PAINT MONO (-3765 5785);
FORCEPROP 0 LASTPIN (-3775 5725) $PN L73
J 0
(-3765 5735);
DISPLAY 0.489362 (-3765 5735);
PAINT MONO (-3765 5735);
FORCEPROP 0 LASTPIN (-3775 5625) $PN L74
J 0
(-3765 5635);
DISPLAY 0.489362 (-3765 5635);
PAINT MONO (-3765 5635);
FORCEPROP 0 LASTPIN (-3775 5575) $PN M72
J 0
(-3765 5585);
DISPLAY 0.489362 (-3765 5585);
PAINT MONO (-3765 5585);
FORCEPROP 0 LASTPIN (-3775 5525) $PN M74
J 0
(-3765 5535);
DISPLAY 0.489362 (-3765 5535);
PAINT MONO (-3765 5535);
FORCEPROP 0 LASTPIN (-3775 5475) $PN N73
J 0
(-3765 5485);
DISPLAY 0.489362 (-3765 5485);
PAINT MONO (-3765 5485);
FORCEPROP 0 LASTPIN (-3775 5425) $PN R74
J 0
(-3765 5435);
DISPLAY 0.489362 (-3765 5435);
PAINT MONO (-3765 5435);
FORCEPROP 0 LASTPIN (-3775 5375) $PN T72
J 0
(-3765 5385);
DISPLAY 0.489362 (-3765 5385);
PAINT MONO (-3765 5385);
FORCEPROP 0 LASTPIN (-3775 5325) $PN T74
J 0
(-3765 5335);
DISPLAY 0.489362 (-3765 5335);
PAINT MONO (-3765 5335);
FORCEPROP 0 LASTPIN (-3775 5275) $PN U73
J 0
(-3765 5285);
DISPLAY 0.489362 (-3765 5285);
PAINT MONO (-3765 5285);
FORCEPROP 0 LASTPIN (-3775 5175) $PN U74
J 0
(-3765 5185);
DISPLAY 0.489362 (-3765 5185);
PAINT MONO (-3765 5185);
FORCEPROP 0 LASTPIN (-3775 5125) $PN V72
J 0
(-3765 5135);
DISPLAY 0.489362 (-3765 5135);
PAINT MONO (-3765 5135);
FORCEPROP 0 LASTPIN (-3775 5075) $PN V74
J 0
(-3765 5085);
DISPLAY 0.489362 (-3765 5085);
PAINT MONO (-3765 5085);
FORCEPROP 0 LASTPIN (-3775 5025) $PN W73
J 0
(-3765 5035);
DISPLAY 0.489362 (-3765 5035);
PAINT MONO (-3765 5035);
FORCEPROP 0 LASTPIN (-3775 4975) $PN AA74
J 0
(-3765 4985);
DISPLAY 0.489362 (-3765 4985);
PAINT MONO (-3765 4985);
FORCEPROP 0 LASTPIN (-3775 4925) $PN AB72
J 0
(-3765 4935);
DISPLAY 0.489362 (-3765 4935);
PAINT MONO (-3765 4935);
FORCEPROP 0 LASTPIN (-3775 4875) $PN AB74
J 0
(-3765 4885);
DISPLAY 0.489362 (-3765 4885);
PAINT MONO (-3765 4885);
FORCEPROP 0 LASTPIN (-3775 4825) $PN AC73
J 0
(-3765 4835);
DISPLAY 0.489362 (-3765 4835);
PAINT MONO (-3765 4835);
FORCEPROP 0 LASTPIN (-3775 4725) $PN AC74
J 0
(-3765 4735);
DISPLAY 0.489362 (-3765 4735);
PAINT MONO (-3765 4735);
FORCEPROP 0 LASTPIN (-3775 4675) $PN AD72
J 0
(-3765 4685);
DISPLAY 0.489362 (-3765 4685);
PAINT MONO (-3765 4685);
FORCEPROP 0 LASTPIN (-3775 4625) $PN AD74
J 0
(-3765 4635);
DISPLAY 0.489362 (-3765 4635);
PAINT MONO (-3765 4635);
FORCEPROP 0 LASTPIN (-3775 4575) $PN AE73
J 0
(-3765 4585);
DISPLAY 0.489362 (-3765 4585);
PAINT MONO (-3765 4585);
FORCEPROP 0 LASTPIN (-3775 4525) $PN AG74
J 0
(-3765 4535);
DISPLAY 0.489362 (-3765 4535);
PAINT MONO (-3765 4535);
FORCEPROP 0 LASTPIN (-3775 4475) $PN AH72
J 0
(-3765 4485);
DISPLAY 0.489362 (-3765 4485);
PAINT MONO (-3765 4485);
FORCEPROP 0 LASTPIN (-3775 4425) $PN AH74
J 0
(-3765 4435);
DISPLAY 0.489362 (-3765 4435);
PAINT MONO (-3765 4435);
FORCEPROP 0 LASTPIN (-3775 4375) $PN AJ73
J 0
(-3765 4385);
DISPLAY 0.489362 (-3765 4385);
PAINT MONO (-3765 4385);
FORCEPROP 0 LASTPIN (-5375 6075) $PN G74
J 2
(-5385 6085);
DISPLAY 0.489362 (-5385 6085);
PAINT MONO (-5385 6085);
FORCEPROP 0 LASTPIN (-5375 5975) $PN N74
J 2
(-5385 5985);
DISPLAY 0.489362 (-5385 5985);
PAINT MONO (-5385 5985);
FORCEPROP 0 LASTPIN (-5375 5875) $PN W74
J 2
(-5385 5885);
DISPLAY 0.489362 (-5385 5885);
PAINT MONO (-5385 5885);
FORCEPROP 0 LASTPIN (-5375 5775) $PN AE74
J 2
(-5385 5785);
DISPLAY 0.489362 (-5385 5785);
PAINT MONO (-5385 5785);
FORCEPROP 0 LASTPIN (-5375 5675) $PN AL74
J 2
(-5385 5685);
DISPLAY 0.489362 (-5385 5685);
PAINT MONO (-5385 5685);
FORCEPROP 0 LASTPIN (-5375 5575) $PN J73
J 2
(-5385 5585);
DISPLAY 0.489362 (-5385 5585);
PAINT MONO (-5385 5585);
FORCEPROP 0 LASTPIN (-5375 5475) $PN R73
J 2
(-5385 5485);
DISPLAY 0.489362 (-5385 5485);
PAINT MONO (-5385 5485);
FORCEPROP 0 LASTPIN (-5375 5375) $PN AA73
J 2
(-5385 5385);
DISPLAY 0.489362 (-5385 5385);
PAINT MONO (-5385 5385);
FORCEPROP 0 LASTPIN (-5375 5275) $PN AG73
J 2
(-5385 5285);
DISPLAY 0.489362 (-5385 5285);
PAINT MONO (-5385 5285);
FORCEPROP 0 LASTPIN (-5375 5175) $PN AN73
J 2
(-5385 5185);
DISPLAY 0.489362 (-5385 5185);
PAINT MONO (-5385 5185);
FORCEPROP 0 LASTPIN (-5375 6025) $PN H74
J 2
(-5385 6035);
DISPLAY 0.489362 (-5385 6035);
PAINT MONO (-5385 6035);
FORCEPROP 0 LASTPIN (-5375 5925) $PN P74
J 2
(-5385 5935);
DISPLAY 0.489362 (-5385 5935);
PAINT MONO (-5385 5935);
FORCEPROP 0 LASTPIN (-5375 5825) $PN Y74
J 2
(-5385 5835);
DISPLAY 0.489362 (-5385 5835);
PAINT MONO (-5385 5835);
FORCEPROP 0 LASTPIN (-5375 5725) $PN AF74
J 2
(-5385 5735);
DISPLAY 0.489362 (-5385 5735);
PAINT MONO (-5385 5735);
FORCEPROP 0 LASTPIN (-5375 5625) $PN AM74
J 2
(-5385 5635);
DISPLAY 0.489362 (-5385 5635);
PAINT MONO (-5385 5635);
FORCEPROP 0 LASTPIN (-5375 5525) $PN H72
J 2
(-5385 5535);
DISPLAY 0.489362 (-5385 5535);
PAINT MONO (-5385 5535);
FORCEPROP 0 LASTPIN (-5375 5425) $PN P72
J 2
(-5385 5435);
DISPLAY 0.489362 (-5385 5435);
PAINT MONO (-5385 5435);
FORCEPROP 0 LASTPIN (-5375 5325) $PN Y72
J 2
(-5385 5335);
DISPLAY 0.489362 (-5385 5335);
PAINT MONO (-5385 5335);
FORCEPROP 0 LASTPIN (-5375 5225) $PN AF72
J 2
(-5385 5235);
DISPLAY 0.489362 (-5385 5235);
PAINT MONO (-5385 5235);
FORCEPROP 0 LASTPIN (-5375 5125) $PN AM72
J 2
(-5385 5135);
DISPLAY 0.489362 (-5385 5135);
PAINT MONO (-5385 5135);
FORCEPROP 0 LASTPIN (-5375 2675) $PN BC73
J 2
(-5385 2685);
DISPLAY 0.489362 (-5385 2685);
PAINT MONO (-5385 2685);
FORCEPROP 0 LASTPIN (-5375 2575) $PN BM72
J 2
(-5385 2585);
DISPLAY 0.489362 (-5385 2585);
PAINT MONO (-5385 2585);
FORCEPROP 0 LASTPIN (-5375 2525) $PN BN74
J 2
(-5385 2535);
DISPLAY 0.489362 (-5385 2535);
PAINT MONO (-5385 2535);
FORCEPROP 0 LASTPIN (-5375 2425) $PN BP74
J 2
(-5385 2435);
DISPLAY 0.489362 (-5385 2435);
PAINT MONO (-5385 2435);
FORCEPROP 0 LASTPIN (-5375 1525) $PN BL73
J 2
(-5385 1535);
DISPLAY 0.489362 (-5385 1535);
PAINT MONO (-5385 1535);
FORCEPROP 0 LASTPIN (-5375 1475) $PN BM74
J 2
(-5385 1485);
DISPLAY 0.489362 (-5385 1485);
PAINT MONO (-5385 1485);
FORCEPROP 0 LASTPIN (-5375 1375) $PN BR74
J 2
(-5385 1385);
DISPLAY 0.489362 (-5385 1385);
PAINT MONO (-5385 1385);
FORCEPROP 0 LASTPIN (-5375 3525) $PN BG73
J 2
(-5385 3535);
DISPLAY 0.489362 (-5385 3535);
PAINT MONO (-5385 3535);
FORCEPROP 0 LASTPIN (-5375 3475) $PN BH72
J 2
(-5385 3485);
DISPLAY 0.489362 (-5385 3485);
PAINT MONO (-5385 3485);
FORCEPROP 0 LASTPIN (-5375 3425) $PN BH74
J 2
(-5385 3435);
DISPLAY 0.489362 (-5385 3435);
PAINT MONO (-5385 3435);
FORCEPROP 0 LASTPIN (-5375 3375) $PN BJ74
J 2
(-5385 3385);
DISPLAY 0.489362 (-5385 3385);
PAINT MONO (-5385 3385);
FORCEPROP 0 LASTPIN (-5375 3325) $PN BJ73
J 2
(-5385 3335);
DISPLAY 0.489362 (-5385 3335);
PAINT MONO (-5385 3335);
FORCEPROP 0 LASTPIN (-5375 3275) $PN BK72
J 2
(-5385 3285);
DISPLAY 0.489362 (-5385 3285);
PAINT MONO (-5385 3285);
FORCEPROP 0 LASTPIN (-5375 3225) $PN BK74
J 2
(-5385 3235);
DISPLAY 0.489362 (-5385 3235);
PAINT MONO (-5385 3235);
FORCEPROP 0 LASTPIN (-3775 2025) $PN BY74
J 0
(-3765 2035);
DISPLAY 0.489362 (-3765 2035);
PAINT MONO (-3765 2035);
FORCEPROP 0 LASTPIN (-3775 1975) $PN CA73
J 0
(-3765 1985);
DISPLAY 0.489362 (-3765 1985);
PAINT MONO (-3765 1985);
FORCEPROP 0 LASTPIN (-3775 1925) $PN CA74
J 0
(-3765 1935);
DISPLAY 0.489362 (-3765 1935);
PAINT MONO (-3765 1935);
FORCEPROP 0 LASTPIN (-3775 1875) $PN CB72
J 0
(-3765 1885);
DISPLAY 0.489362 (-3765 1885);
PAINT MONO (-3765 1885);
FORCEPROP 0 LASTPIN (-3775 1825) $PN BT74
J 0
(-3765 1835);
DISPLAY 0.489362 (-3765 1835);
PAINT MONO (-3765 1835);
FORCEPROP 0 LASTPIN (-3775 1775) $PN BU73
J 0
(-3765 1785);
DISPLAY 0.489362 (-3765 1785);
PAINT MONO (-3765 1785);
FORCEPROP 0 LASTPIN (-3775 1725) $PN BU74
J 0
(-3765 1735);
DISPLAY 0.489362 (-3765 1735);
PAINT MONO (-3765 1735);
FORCEPROP 0 LASTPIN (-3775 1675) $PN BV72
J 0
(-3765 1685);
DISPLAY 0.489362 (-3765 1685);
PAINT MONO (-3765 1685);
FORCEPROP 0 LASTPIN (-3775 4275) $PN CB74
J 0
(-3765 4285);
DISPLAY 0.489362 (-3765 4285);
PAINT MONO (-3765 4285);
FORCEPROP 0 LASTPIN (-3775 4225) $PN CC73
J 0
(-3765 4235);
DISPLAY 0.489362 (-3765 4235);
PAINT MONO (-3765 4235);
FORCEPROP 0 LASTPIN (-3775 4175) $PN CC74
J 0
(-3765 4185);
DISPLAY 0.489362 (-3765 4185);
PAINT MONO (-3765 4185);
FORCEPROP 0 LASTPIN (-3775 4125) $PN CD72
J 0
(-3765 4135);
DISPLAY 0.489362 (-3765 4135);
PAINT MONO (-3765 4135);
FORCEPROP 0 LASTPIN (-3775 4075) $PN CF74
J 0
(-3765 4085);
DISPLAY 0.489362 (-3765 4085);
PAINT MONO (-3765 4085);
FORCEPROP 0 LASTPIN (-3775 4025) $PN CG73
J 0
(-3765 4035);
DISPLAY 0.489362 (-3765 4035);
PAINT MONO (-3765 4035);
FORCEPROP 0 LASTPIN (-3775 3975) $PN CG74
J 0
(-3765 3985);
DISPLAY 0.489362 (-3765 3985);
PAINT MONO (-3765 3985);
FORCEPROP 0 LASTPIN (-3775 3925) $PN CH72
J 0
(-3765 3935);
DISPLAY 0.489362 (-3765 3935);
PAINT MONO (-3765 3935);
FORCEPROP 0 LASTPIN (-3775 3825) $PN CH74
J 0
(-3765 3835);
DISPLAY 0.489362 (-3765 3835);
PAINT MONO (-3765 3835);
FORCEPROP 0 LASTPIN (-3775 3775) $PN CJ73
J 0
(-3765 3785);
DISPLAY 0.489362 (-3765 3785);
PAINT MONO (-3765 3785);
FORCEPROP 0 LASTPIN (-3775 3725) $PN CJ74
J 0
(-3765 3735);
DISPLAY 0.489362 (-3765 3735);
PAINT MONO (-3765 3735);
FORCEPROP 0 LASTPIN (-3775 3675) $PN CK72
J 0
(-3765 3685);
DISPLAY 0.489362 (-3765 3685);
PAINT MONO (-3765 3685);
FORCEPROP 0 LASTPIN (-3775 3625) $PN CM74
J 0
(-3765 3635);
DISPLAY 0.489362 (-3765 3635);
PAINT MONO (-3765 3635);
FORCEPROP 0 LASTPIN (-3775 3575) $PN CN73
J 0
(-3765 3585);
DISPLAY 0.489362 (-3765 3585);
PAINT MONO (-3765 3585);
FORCEPROP 0 LASTPIN (-3775 3525) $PN CN74
J 0
(-3765 3535);
DISPLAY 0.489362 (-3765 3535);
PAINT MONO (-3765 3535);
FORCEPROP 0 LASTPIN (-3775 3475) $PN CP72
J 0
(-3765 3485);
DISPLAY 0.489362 (-3765 3485);
PAINT MONO (-3765 3485);
FORCEPROP 0 LASTPIN (-3775 3375) $PN CP74
J 0
(-3765 3385);
DISPLAY 0.489362 (-3765 3385);
PAINT MONO (-3765 3385);
FORCEPROP 0 LASTPIN (-3775 3325) $PN CR73
J 0
(-3765 3335);
DISPLAY 0.489362 (-3765 3335);
PAINT MONO (-3765 3335);
FORCEPROP 0 LASTPIN (-3775 3275) $PN CR74
J 0
(-3765 3285);
DISPLAY 0.489362 (-3765 3285);
PAINT MONO (-3765 3285);
FORCEPROP 0 LASTPIN (-3775 3225) $PN CT72
J 0
(-3765 3235);
DISPLAY 0.489362 (-3765 3235);
PAINT MONO (-3765 3235);
FORCEPROP 0 LASTPIN (-3775 3175) $PN CV74
J 0
(-3765 3185);
DISPLAY 0.489362 (-3765 3185);
PAINT MONO (-3765 3185);
FORCEPROP 0 LASTPIN (-3775 3125) $PN CW73
J 0
(-3765 3135);
DISPLAY 0.489362 (-3765 3135);
PAINT MONO (-3765 3135);
FORCEPROP 0 LASTPIN (-3775 3075) $PN CW74
J 0
(-3765 3085);
DISPLAY 0.489362 (-3765 3085);
PAINT MONO (-3765 3085);
FORCEPROP 0 LASTPIN (-3775 3025) $PN CY72
J 0
(-3765 3035);
DISPLAY 0.489362 (-3765 3035);
PAINT MONO (-3765 3035);
FORCEPROP 0 LASTPIN (-3775 2925) $PN CY74
J 0
(-3765 2935);
DISPLAY 0.489362 (-3765 2935);
PAINT MONO (-3765 2935);
FORCEPROP 0 LASTPIN (-3775 2875) $PN DA73
J 0
(-3765 2885);
DISPLAY 0.489362 (-3765 2885);
PAINT MONO (-3765 2885);
FORCEPROP 0 LASTPIN (-3775 2825) $PN DA74
J 0
(-3765 2835);
DISPLAY 0.489362 (-3765 2835);
PAINT MONO (-3765 2835);
FORCEPROP 0 LASTPIN (-3775 2775) $PN DB72
J 0
(-3765 2785);
DISPLAY 0.489362 (-3765 2785);
PAINT MONO (-3765 2785);
FORCEPROP 0 LASTPIN (-3775 2725) $PN DD74
J 0
(-3765 2735);
DISPLAY 0.489362 (-3765 2735);
PAINT MONO (-3765 2735);
FORCEPROP 0 LASTPIN (-3775 2675) $PN DE73
J 0
(-3765 2685);
DISPLAY 0.489362 (-3765 2685);
PAINT MONO (-3765 2685);
FORCEPROP 0 LASTPIN (-3775 2625) $PN DE74
J 0
(-3765 2635);
DISPLAY 0.489362 (-3765 2635);
PAINT MONO (-3765 2635);
FORCEPROP 0 LASTPIN (-3775 2575) $PN DF74
J 0
(-3765 2585);
DISPLAY 0.489362 (-3765 2585);
PAINT MONO (-3765 2585);
FORCEPROP 0 LASTPIN (-5375 5025) $PN CD74
J 2
(-5385 5035);
DISPLAY 0.489362 (-5385 5035);
PAINT MONO (-5385 5035);
FORCEPROP 0 LASTPIN (-5375 4925) $PN CK74
J 2
(-5385 4935);
DISPLAY 0.489362 (-5385 4935);
PAINT MONO (-5385 4935);
FORCEPROP 0 LASTPIN (-5375 4825) $PN CT74
J 2
(-5385 4835);
DISPLAY 0.489362 (-5385 4835);
PAINT MONO (-5385 4835);
FORCEPROP 0 LASTPIN (-5375 4725) $PN DB74
J 2
(-5385 4735);
DISPLAY 0.489362 (-5385 4735);
PAINT MONO (-5385 4735);
FORCEPROP 0 LASTPIN (-5375 4625) $PN BY72
J 2
(-5385 4635);
DISPLAY 0.489362 (-5385 4635);
PAINT MONO (-5385 4635);
FORCEPROP 0 LASTPIN (-5375 4525) $PN CF72
J 2
(-5385 4535);
DISPLAY 0.489362 (-5385 4535);
PAINT MONO (-5385 4535);
FORCEPROP 0 LASTPIN (-5375 4425) $PN CM72
J 2
(-5385 4435);
DISPLAY 0.489362 (-5385 4435);
PAINT MONO (-5385 4435);
FORCEPROP 0 LASTPIN (-5375 4325) $PN CV72
J 2
(-5385 4335);
DISPLAY 0.489362 (-5385 4335);
PAINT MONO (-5385 4335);
FORCEPROP 0 LASTPIN (-5375 4225) $PN DD72
J 2
(-5385 4235);
DISPLAY 0.489362 (-5385 4235);
PAINT MONO (-5385 4235);
FORCEPROP 0 LASTPIN (-5375 4125) $PN BV74
J 2
(-5385 4135);
DISPLAY 0.489362 (-5385 4135);
PAINT MONO (-5385 4135);
FORCEPROP 0 LASTPIN (-5375 4975) $PN CE74
J 2
(-5385 4985);
DISPLAY 0.489362 (-5385 4985);
PAINT MONO (-5385 4985);
FORCEPROP 0 LASTPIN (-5375 4875) $PN CL74
J 2
(-5385 4885);
DISPLAY 0.489362 (-5385 4885);
PAINT MONO (-5385 4885);
FORCEPROP 0 LASTPIN (-5375 4775) $PN CU74
J 2
(-5385 4785);
DISPLAY 0.489362 (-5385 4785);
PAINT MONO (-5385 4785);
FORCEPROP 0 LASTPIN (-5375 4675) $PN DC74
J 2
(-5385 4685);
DISPLAY 0.489362 (-5385 4685);
PAINT MONO (-5385 4685);
FORCEPROP 0 LASTPIN (-5375 4575) $PN BW73
J 2
(-5385 4585);
DISPLAY 0.489362 (-5385 4585);
PAINT MONO (-5385 4585);
FORCEPROP 0 LASTPIN (-5375 4475) $PN CE73
J 2
(-5385 4485);
DISPLAY 0.489362 (-5385 4485);
PAINT MONO (-5385 4485);
FORCEPROP 0 LASTPIN (-5375 4375) $PN CL73
J 2
(-5385 4385);
DISPLAY 0.489362 (-5385 4385);
PAINT MONO (-5385 4385);
FORCEPROP 0 LASTPIN (-5375 4275) $PN CU73
J 2
(-5385 4285);
DISPLAY 0.489362 (-5385 4285);
PAINT MONO (-5385 4285);
FORCEPROP 0 LASTPIN (-5375 4175) $PN DC73
J 2
(-5385 4185);
DISPLAY 0.489362 (-5385 4185);
PAINT MONO (-5385 4185);
FORCEPROP 0 LASTPIN (-5375 4075) $PN BW74
J 2
(-5385 4085);
DISPLAY 0.489362 (-5385 4085);
PAINT MONO (-5385 4085);
FORCEPROP 0 LASTPIN (-5375 2325) $PN BL74
J 2
(-5385 2335);
DISPLAY 0.489362 (-5385 2335);
PAINT MONO (-5385 2335);
FORCEPROP 0 LASTPIN (-5375 1275) $PN BF72
J 2
(-5385 1285);
DISPLAY 0.489362 (-5385 1285);
PAINT MONO (-5385 1285);
FORCEPROP 0 LASTPIN (-5375 1225) $PN C60
J 2
(-5385 1235);
DISPLAY 0.489362 (-5385 1235);
PAINT MONO (-5385 1235);
FORCEPROP 2 LAST PART_TYPE SMLF
J 0
(-5225 6375);
DISPLAY 1.021277 (-5225 6375);
FORCEPROP 1 LAST MATERIAL IO
J 0
(-5220 6207);
DISPLAY 0.489362 (-5220 6207);
PAINT SKYBLUE (-5220 6207);
FORCEPROP 2 LAST VALUE SOCKET6096_13568-001
J 0
(-5225 6275);
DISPLAY 0.489362 (-5225 6275);
PAINT SKYBLUE (-5225 6275);
FORCEPROP 2 LAST CDS_LIB pure_quanta
J 0
(-4575 3675);
DISPLAY INVISIBLE (-4575 3675);
FORCEPROP 1 LAST NEEDS_NO_SIZE TRUE
J 0
(-4575 3675);
DISPLAY 0.723404 (-4575 3675);
PAINT GREEN (-4575 3675);
DISPLAY INVISIBLE (-4575 3675);
FORCEPROP 1 LAST CDS_LMAN_SYM_OUTLINE -650,2500,650,-2500
J 0
(-4575 3675);
DISPLAY 0.468085 (-4575 3675);
PAINT GREEN (-4575 3675);
DISPLAY INVISIBLE (-4575 3675);
FORCEPROP 1 LAST PATH I167
J 0
(-4575 3675);
DISPLAY 0.723404 (-4575 3675);
PAINT GREEN (-4575 3675);
DISPLAY INVISIBLE (-4575 3675);
FORCEPROP 1 LAST PART_NUMBER DGA^6000030
J 0
(-5220 6334);
DISPLAY 0.489362 (-5220 6334);
PAINT SKYBLUE (-5220 6334);
DISPLAY INVISIBLE (-5220 6334);
FORCEADD OFFPAGE..3
(-2575 6100);
FORCEPROP 2 LAST $XR0 98 
J 0
(-2361 6100);
DISPLAY 0.638298 (-2361 6100);
PAINT MONO (-2361 6100);
FORCEPROP 2 LAST CDS_LIB mstr_standard
J 0
(-2575 6100);
DISPLAY 0.723404 (-2575 6100);
PAINT MONO (-2575 6100);
DISPLAY INVISIBLE (-2575 6100);
FORCEPROP 1 LAST OFFPAGE TRUE
J 0
(-2250 5975);
DISPLAY 0.872340 (-2250 5975);
PAINT GREEN (-2250 5975);
DISPLAY INVISIBLE (-2250 5975);
FORCEPROP 1 LAST COMMENT_BODY TRUE
J 0
(-2625 6000);
DISPLAY 0.872340 (-2625 6000);
PAINT GREEN (-2625 6000);
DISPLAY INVISIBLE (-2625 6000);
FORCEPROP 2 LAST PATH I168
J 0
(-2350 6150);
DISPLAY 1.021277 (-2350 6150);
DISPLAY INVISIBLE (-2350 6150);
FORCEADD OFFPAGE..3
(-2575 4300);
FORCEPROP 2 LAST $XR0 98 
J 0
(-2361 4300);
DISPLAY 0.638298 (-2361 4300);
PAINT MONO (-2361 4300);
FORCEPROP 2 LAST CDS_LIB mstr_standard
J 0
(-2575 4300);
DISPLAY 0.723404 (-2575 4300);
PAINT MONO (-2575 4300);
DISPLAY INVISIBLE (-2575 4300);
FORCEPROP 1 LAST OFFPAGE TRUE
J 0
(-2250 4175);
DISPLAY 0.872340 (-2250 4175);
PAINT GREEN (-2250 4175);
DISPLAY INVISIBLE (-2250 4175);
FORCEPROP 1 LAST COMMENT_BODY TRUE
J 0
(-2625 4200);
DISPLAY 0.872340 (-2625 4200);
PAINT GREEN (-2625 4200);
DISPLAY INVISIBLE (-2625 4200);
FORCEPROP 2 LAST PATH I169
J 0
(-2350 4350);
DISPLAY 1.021277 (-2350 4350);
DISPLAY INVISIBLE (-2350 4350);
FORCEADD TAP..1
(-3300 6025);
FORCEPROP 3 LASTPIN (-3350 6025) SIG_NAME M_A_CPU1_SA_DQ<1>
J 0
(-3340 6035);
DISPLAY 0.659574 (-3340 6035);
PAINT MONO (-3340 6035);
DISPLAY INVISIBLE (-3340 6035);
FORCEPROP 1 LASTPIN (-3350 6025) BN 1
J 0
(-3362 6033);
DISPLAY 0.489362 (-3362 6033);
PAINT GREEN (-3362 6033);
FORCEPROP 2 LAST CDS_LIB mstr_standard
J 0
(-3300 6025);
DISPLAY 0.723404 (-3300 6025);
PAINT MONO (-3300 6025);
DISPLAY INVISIBLE (-3300 6025);
FORCEPROP 1 LAST BODY_TYPE PLUMBING
J 0
(-3300 6075);
DISPLAY 0.872340 (-3300 6075);
PAINT GREEN (-3300 6075);
DISPLAY INVISIBLE (-3300 6075);
FORCEPROP 1 LAST HDL_TAP TRUE
J 0
(-2975 5900);
DISPLAY 0.872340 (-2975 5900);
DISPLAY INVISIBLE (-2975 5900);
FORCEPROP 1 LAST PATH I170
J 0
(-3302 6025);
DISPLAY 0.872340 (-3302 6025);
PAINT GREEN (-3302 6025);
DISPLAY INVISIBLE (-3302 6025);
FORCEADD TAP..1
(-3300 6075);
FORCEPROP 3 LASTPIN (-3350 6075) SIG_NAME M_A_CPU1_SA_DQ<0>
J 0
(-3340 6085);
DISPLAY 0.659574 (-3340 6085);
PAINT MONO (-3340 6085);
DISPLAY INVISIBLE (-3340 6085);
FORCEPROP 1 LASTPIN (-3350 6075) BN 0
J 0
(-3362 6083);
DISPLAY 0.489362 (-3362 6083);
PAINT GREEN (-3362 6083);
FORCEPROP 2 LAST CDS_LIB mstr_standard
J 0
(-3300 6075);
DISPLAY 0.723404 (-3300 6075);
PAINT MONO (-3300 6075);
DISPLAY INVISIBLE (-3300 6075);
FORCEPROP 1 LAST BODY_TYPE PLUMBING
J 0
(-3300 6125);
DISPLAY 0.872340 (-3300 6125);
PAINT GREEN (-3300 6125);
DISPLAY INVISIBLE (-3300 6125);
FORCEPROP 1 LAST HDL_TAP TRUE
J 0
(-2975 5950);
DISPLAY 0.872340 (-2975 5950);
DISPLAY INVISIBLE (-2975 5950);
FORCEPROP 1 LAST PATH I171
J 0
(-3302 6075);
DISPLAY 0.872340 (-3302 6075);
PAINT GREEN (-3302 6075);
DISPLAY INVISIBLE (-3302 6075);
FORCEADD TAP..1
(-3300 5975);
FORCEPROP 3 LASTPIN (-3350 5975) SIG_NAME M_A_CPU1_SA_DQ<2>
J 0
(-3340 5985);
DISPLAY 0.659574 (-3340 5985);
PAINT MONO (-3340 5985);
DISPLAY INVISIBLE (-3340 5985);
FORCEPROP 1 LASTPIN (-3350 5975) BN 2
J 0
(-3362 5983);
DISPLAY 0.489362 (-3362 5983);
PAINT GREEN (-3362 5983);
FORCEPROP 2 LAST CDS_LIB mstr_standard
J 0
(-3300 5975);
DISPLAY 0.723404 (-3300 5975);
PAINT MONO (-3300 5975);
DISPLAY INVISIBLE (-3300 5975);
FORCEPROP 1 LAST BODY_TYPE PLUMBING
J 0
(-3300 6025);
DISPLAY 0.872340 (-3300 6025);
PAINT GREEN (-3300 6025);
DISPLAY INVISIBLE (-3300 6025);
FORCEPROP 1 LAST HDL_TAP TRUE
J 0
(-2975 5850);
DISPLAY 0.872340 (-2975 5850);
DISPLAY INVISIBLE (-2975 5850);
FORCEPROP 1 LAST PATH I172
J 0
(-3302 5975);
DISPLAY 0.872340 (-3302 5975);
PAINT GREEN (-3302 5975);
DISPLAY INVISIBLE (-3302 5975);
FORCEADD TAP..1
(-3300 5925);
FORCEPROP 3 LASTPIN (-3350 5925) SIG_NAME M_A_CPU1_SA_DQ<3>
J 0
(-3340 5935);
DISPLAY 0.659574 (-3340 5935);
PAINT MONO (-3340 5935);
DISPLAY INVISIBLE (-3340 5935);
FORCEPROP 1 LASTPIN (-3350 5925) BN 3
J 0
(-3362 5933);
DISPLAY 0.489362 (-3362 5933);
PAINT GREEN (-3362 5933);
FORCEPROP 2 LAST CDS_LIB mstr_standard
J 0
(-3300 5925);
DISPLAY 0.723404 (-3300 5925);
PAINT MONO (-3300 5925);
DISPLAY INVISIBLE (-3300 5925);
FORCEPROP 1 LAST BODY_TYPE PLUMBING
J 0
(-3300 5975);
DISPLAY 0.872340 (-3300 5975);
PAINT GREEN (-3300 5975);
DISPLAY INVISIBLE (-3300 5975);
FORCEPROP 1 LAST HDL_TAP TRUE
J 0
(-2975 5800);
DISPLAY 0.872340 (-2975 5800);
DISPLAY INVISIBLE (-2975 5800);
FORCEPROP 1 LAST PATH I173
J 0
(-3302 5925);
DISPLAY 0.872340 (-3302 5925);
PAINT GREEN (-3302 5925);
DISPLAY INVISIBLE (-3302 5925);
FORCEADD TAP..1
(-3300 5825);
FORCEPROP 3 LASTPIN (-3350 5825) SIG_NAME M_A_CPU1_SA_DQ<5>
J 0
(-3340 5835);
DISPLAY 0.659574 (-3340 5835);
PAINT MONO (-3340 5835);
DISPLAY INVISIBLE (-3340 5835);
FORCEPROP 1 LASTPIN (-3350 5825) BN 5
J 0
(-3362 5833);
DISPLAY 0.489362 (-3362 5833);
PAINT GREEN (-3362 5833);
FORCEPROP 2 LAST CDS_LIB mstr_standard
J 0
(-3300 5825);
DISPLAY 0.723404 (-3300 5825);
PAINT MONO (-3300 5825);
DISPLAY INVISIBLE (-3300 5825);
FORCEPROP 1 LAST BODY_TYPE PLUMBING
J 0
(-3300 5875);
DISPLAY 0.872340 (-3300 5875);
PAINT GREEN (-3300 5875);
DISPLAY INVISIBLE (-3300 5875);
FORCEPROP 1 LAST HDL_TAP TRUE
J 0
(-2975 5700);
DISPLAY 0.872340 (-2975 5700);
DISPLAY INVISIBLE (-2975 5700);
FORCEPROP 1 LAST PATH I174
J 0
(-3302 5825);
DISPLAY 0.872340 (-3302 5825);
PAINT GREEN (-3302 5825);
DISPLAY INVISIBLE (-3302 5825);
FORCEADD TAP..1
(-3300 5875);
FORCEPROP 3 LASTPIN (-3350 5875) SIG_NAME M_A_CPU1_SA_DQ<4>
J 0
(-3340 5885);
DISPLAY 0.659574 (-3340 5885);
PAINT MONO (-3340 5885);
DISPLAY INVISIBLE (-3340 5885);
FORCEPROP 1 LASTPIN (-3350 5875) BN 4
J 0
(-3362 5883);
DISPLAY 0.489362 (-3362 5883);
PAINT GREEN (-3362 5883);
FORCEPROP 2 LAST CDS_LIB mstr_standard
J 0
(-3300 5875);
DISPLAY 0.723404 (-3300 5875);
PAINT MONO (-3300 5875);
DISPLAY INVISIBLE (-3300 5875);
FORCEPROP 1 LAST BODY_TYPE PLUMBING
J 0
(-3300 5925);
DISPLAY 0.872340 (-3300 5925);
PAINT GREEN (-3300 5925);
DISPLAY INVISIBLE (-3300 5925);
FORCEPROP 1 LAST HDL_TAP TRUE
J 0
(-2975 5750);
DISPLAY 0.872340 (-2975 5750);
DISPLAY INVISIBLE (-2975 5750);
FORCEPROP 1 LAST PATH I175
J 0
(-3302 5875);
DISPLAY 0.872340 (-3302 5875);
PAINT GREEN (-3302 5875);
DISPLAY INVISIBLE (-3302 5875);
FORCEADD TAP..1
(-3300 5775);
FORCEPROP 3 LASTPIN (-3350 5775) SIG_NAME M_A_CPU1_SA_DQ<6>
J 0
(-3340 5785);
DISPLAY 0.659574 (-3340 5785);
PAINT MONO (-3340 5785);
DISPLAY INVISIBLE (-3340 5785);
FORCEPROP 1 LASTPIN (-3350 5775) BN 6
J 0
(-3362 5783);
DISPLAY 0.489362 (-3362 5783);
PAINT GREEN (-3362 5783);
FORCEPROP 2 LAST CDS_LIB mstr_standard
J 0
(-3300 5775);
DISPLAY 0.723404 (-3300 5775);
PAINT MONO (-3300 5775);
DISPLAY INVISIBLE (-3300 5775);
FORCEPROP 1 LAST BODY_TYPE PLUMBING
J 0
(-3300 5825);
DISPLAY 0.872340 (-3300 5825);
PAINT GREEN (-3300 5825);
DISPLAY INVISIBLE (-3300 5825);
FORCEPROP 1 LAST HDL_TAP TRUE
J 0
(-2975 5650);
DISPLAY 0.872340 (-2975 5650);
DISPLAY INVISIBLE (-2975 5650);
FORCEPROP 1 LAST PATH I176
J 0
(-3302 5775);
DISPLAY 0.872340 (-3302 5775);
PAINT GREEN (-3302 5775);
DISPLAY INVISIBLE (-3302 5775);
FORCEADD TAP..1
(-3300 5725);
FORCEPROP 3 LASTPIN (-3350 5725) SIG_NAME M_A_CPU1_SA_DQ<7>
J 0
(-3340 5735);
DISPLAY 0.659574 (-3340 5735);
PAINT MONO (-3340 5735);
DISPLAY INVISIBLE (-3340 5735);
FORCEPROP 1 LASTPIN (-3350 5725) BN 7
J 0
(-3362 5733);
DISPLAY 0.489362 (-3362 5733);
PAINT GREEN (-3362 5733);
FORCEPROP 2 LAST CDS_LIB mstr_standard
J 0
(-3300 5725);
DISPLAY 0.723404 (-3300 5725);
PAINT MONO (-3300 5725);
DISPLAY INVISIBLE (-3300 5725);
FORCEPROP 1 LAST BODY_TYPE PLUMBING
J 0
(-3300 5775);
DISPLAY 0.872340 (-3300 5775);
PAINT GREEN (-3300 5775);
DISPLAY INVISIBLE (-3300 5775);
FORCEPROP 1 LAST HDL_TAP TRUE
J 0
(-2975 5600);
DISPLAY 0.872340 (-2975 5600);
DISPLAY INVISIBLE (-2975 5600);
FORCEPROP 1 LAST PATH I177
J 0
(-3302 5725);
DISPLAY 0.872340 (-3302 5725);
PAINT GREEN (-3302 5725);
DISPLAY INVISIBLE (-3302 5725);
FORCEADD TAP..1
(-3300 5575);
FORCEPROP 3 LASTPIN (-3350 5575) SIG_NAME M_A_CPU1_SA_DQ<9>
J 0
(-3340 5585);
DISPLAY 0.659574 (-3340 5585);
PAINT MONO (-3340 5585);
DISPLAY INVISIBLE (-3340 5585);
FORCEPROP 1 LASTPIN (-3350 5575) BN 9
J 0
(-3362 5583);
DISPLAY 0.489362 (-3362 5583);
PAINT GREEN (-3362 5583);
FORCEPROP 2 LAST CDS_LIB mstr_standard
J 0
(-3300 5575);
DISPLAY 0.723404 (-3300 5575);
PAINT MONO (-3300 5575);
DISPLAY INVISIBLE (-3300 5575);
FORCEPROP 1 LAST BODY_TYPE PLUMBING
J 0
(-3300 5625);
DISPLAY 0.872340 (-3300 5625);
PAINT GREEN (-3300 5625);
DISPLAY INVISIBLE (-3300 5625);
FORCEPROP 1 LAST HDL_TAP TRUE
J 0
(-2975 5450);
DISPLAY 0.872340 (-2975 5450);
DISPLAY INVISIBLE (-2975 5450);
FORCEPROP 1 LAST PATH I178
J 0
(-3302 5575);
DISPLAY 0.872340 (-3302 5575);
PAINT GREEN (-3302 5575);
DISPLAY INVISIBLE (-3302 5575);
FORCEADD TAP..1
(-3300 5625);
FORCEPROP 3 LASTPIN (-3350 5625) SIG_NAME M_A_CPU1_SA_DQ<8>
J 0
(-3340 5635);
DISPLAY 0.659574 (-3340 5635);
PAINT MONO (-3340 5635);
DISPLAY INVISIBLE (-3340 5635);
FORCEPROP 1 LASTPIN (-3350 5625) BN 8
J 0
(-3362 5633);
DISPLAY 0.489362 (-3362 5633);
PAINT GREEN (-3362 5633);
FORCEPROP 2 LAST CDS_LIB mstr_standard
J 0
(-3300 5625);
DISPLAY 0.723404 (-3300 5625);
PAINT MONO (-3300 5625);
DISPLAY INVISIBLE (-3300 5625);
FORCEPROP 1 LAST BODY_TYPE PLUMBING
J 0
(-3300 5675);
DISPLAY 0.872340 (-3300 5675);
PAINT GREEN (-3300 5675);
DISPLAY INVISIBLE (-3300 5675);
FORCEPROP 1 LAST HDL_TAP TRUE
J 0
(-2975 5500);
DISPLAY 0.872340 (-2975 5500);
DISPLAY INVISIBLE (-2975 5500);
FORCEPROP 1 LAST PATH I179
J 0
(-3302 5625);
DISPLAY 0.872340 (-3302 5625);
PAINT GREEN (-3302 5625);
DISPLAY INVISIBLE (-3302 5625);
FORCEADD TAP..1
(-3300 5525);
FORCEPROP 3 LASTPIN (-3350 5525) SIG_NAME M_A_CPU1_SA_DQ<10>
J 0
(-3340 5535);
DISPLAY 0.659574 (-3340 5535);
PAINT MONO (-3340 5535);
DISPLAY INVISIBLE (-3340 5535);
FORCEPROP 1 LASTPIN (-3350 5525) BN 10
J 0
(-3362 5533);
DISPLAY 0.489362 (-3362 5533);
PAINT GREEN (-3362 5533);
FORCEPROP 2 LAST CDS_LIB mstr_standard
J 0
(-3300 5525);
DISPLAY 0.723404 (-3300 5525);
PAINT MONO (-3300 5525);
DISPLAY INVISIBLE (-3300 5525);
FORCEPROP 1 LAST BODY_TYPE PLUMBING
J 0
(-3300 5575);
DISPLAY 0.872340 (-3300 5575);
PAINT GREEN (-3300 5575);
DISPLAY INVISIBLE (-3300 5575);
FORCEPROP 1 LAST HDL_TAP TRUE
J 0
(-2975 5400);
DISPLAY 0.872340 (-2975 5400);
DISPLAY INVISIBLE (-2975 5400);
FORCEPROP 1 LAST PATH I180
J 0
(-3302 5525);
DISPLAY 0.872340 (-3302 5525);
PAINT GREEN (-3302 5525);
DISPLAY INVISIBLE (-3302 5525);
FORCEADD TAP..1
(-3300 5425);
FORCEPROP 3 LASTPIN (-3350 5425) SIG_NAME M_A_CPU1_SA_DQ<12>
J 0
(-3340 5435);
DISPLAY 0.659574 (-3340 5435);
PAINT MONO (-3340 5435);
DISPLAY INVISIBLE (-3340 5435);
FORCEPROP 1 LASTPIN (-3350 5425) BN 12
J 0
(-3362 5433);
DISPLAY 0.489362 (-3362 5433);
PAINT GREEN (-3362 5433);
FORCEPROP 2 LAST CDS_LIB mstr_standard
J 0
(-3300 5425);
DISPLAY 0.723404 (-3300 5425);
PAINT MONO (-3300 5425);
DISPLAY INVISIBLE (-3300 5425);
FORCEPROP 1 LAST BODY_TYPE PLUMBING
J 0
(-3300 5475);
DISPLAY 0.872340 (-3300 5475);
PAINT GREEN (-3300 5475);
DISPLAY INVISIBLE (-3300 5475);
FORCEPROP 1 LAST HDL_TAP TRUE
J 0
(-2975 5300);
DISPLAY 0.872340 (-2975 5300);
DISPLAY INVISIBLE (-2975 5300);
FORCEPROP 1 LAST PATH I181
J 0
(-3302 5425);
DISPLAY 0.872340 (-3302 5425);
PAINT GREEN (-3302 5425);
DISPLAY INVISIBLE (-3302 5425);
FORCEADD TAP..1
(-3300 5475);
FORCEPROP 3 LASTPIN (-3350 5475) SIG_NAME M_A_CPU1_SA_DQ<11>
J 0
(-3340 5485);
DISPLAY 0.659574 (-3340 5485);
PAINT MONO (-3340 5485);
DISPLAY INVISIBLE (-3340 5485);
FORCEPROP 1 LASTPIN (-3350 5475) BN 11
J 0
(-3362 5483);
DISPLAY 0.489362 (-3362 5483);
PAINT GREEN (-3362 5483);
FORCEPROP 2 LAST CDS_LIB mstr_standard
J 0
(-3300 5475);
DISPLAY 0.723404 (-3300 5475);
PAINT MONO (-3300 5475);
DISPLAY INVISIBLE (-3300 5475);
FORCEPROP 1 LAST BODY_TYPE PLUMBING
J 0
(-3300 5525);
DISPLAY 0.872340 (-3300 5525);
PAINT GREEN (-3300 5525);
DISPLAY INVISIBLE (-3300 5525);
FORCEPROP 1 LAST HDL_TAP TRUE
J 0
(-2975 5350);
DISPLAY 0.872340 (-2975 5350);
DISPLAY INVISIBLE (-2975 5350);
FORCEPROP 1 LAST PATH I182
J 0
(-3302 5475);
DISPLAY 0.872340 (-3302 5475);
PAINT GREEN (-3302 5475);
DISPLAY INVISIBLE (-3302 5475);
FORCEADD TAP..1
(-3300 5325);
FORCEPROP 3 LASTPIN (-3350 5325) SIG_NAME M_A_CPU1_SA_DQ<14>
J 0
(-3340 5335);
DISPLAY 0.659574 (-3340 5335);
PAINT MONO (-3340 5335);
DISPLAY INVISIBLE (-3340 5335);
FORCEPROP 1 LASTPIN (-3350 5325) BN 14
J 0
(-3362 5333);
DISPLAY 0.489362 (-3362 5333);
PAINT GREEN (-3362 5333);
FORCEPROP 2 LAST CDS_LIB mstr_standard
J 0
(-3300 5325);
DISPLAY 0.723404 (-3300 5325);
PAINT MONO (-3300 5325);
DISPLAY INVISIBLE (-3300 5325);
FORCEPROP 1 LAST BODY_TYPE PLUMBING
J 0
(-3300 5375);
DISPLAY 0.872340 (-3300 5375);
PAINT GREEN (-3300 5375);
DISPLAY INVISIBLE (-3300 5375);
FORCEPROP 1 LAST HDL_TAP TRUE
J 0
(-2975 5200);
DISPLAY 0.872340 (-2975 5200);
DISPLAY INVISIBLE (-2975 5200);
FORCEPROP 1 LAST PATH I183
J 0
(-3302 5325);
DISPLAY 0.872340 (-3302 5325);
PAINT GREEN (-3302 5325);
DISPLAY INVISIBLE (-3302 5325);
FORCEADD TAP..1
(-3300 5375);
FORCEPROP 3 LASTPIN (-3350 5375) SIG_NAME M_A_CPU1_SA_DQ<13>
J 0
(-3340 5385);
DISPLAY 0.659574 (-3340 5385);
PAINT MONO (-3340 5385);
DISPLAY INVISIBLE (-3340 5385);
FORCEPROP 1 LASTPIN (-3350 5375) BN 13
J 0
(-3362 5383);
DISPLAY 0.489362 (-3362 5383);
PAINT GREEN (-3362 5383);
FORCEPROP 2 LAST CDS_LIB mstr_standard
J 0
(-3300 5375);
DISPLAY 0.723404 (-3300 5375);
PAINT MONO (-3300 5375);
DISPLAY INVISIBLE (-3300 5375);
FORCEPROP 1 LAST BODY_TYPE PLUMBING
J 0
(-3300 5425);
DISPLAY 0.872340 (-3300 5425);
PAINT GREEN (-3300 5425);
DISPLAY INVISIBLE (-3300 5425);
FORCEPROP 1 LAST HDL_TAP TRUE
J 0
(-2975 5250);
DISPLAY 0.872340 (-2975 5250);
DISPLAY INVISIBLE (-2975 5250);
FORCEPROP 1 LAST PATH I184
J 0
(-3302 5375);
DISPLAY 0.872340 (-3302 5375);
PAINT GREEN (-3302 5375);
DISPLAY INVISIBLE (-3302 5375);
FORCEADD TAP..1
(-3300 5275);
FORCEPROP 3 LASTPIN (-3350 5275) SIG_NAME M_A_CPU1_SA_DQ<15>
J 0
(-3340 5285);
DISPLAY 0.659574 (-3340 5285);
PAINT MONO (-3340 5285);
DISPLAY INVISIBLE (-3340 5285);
FORCEPROP 1 LASTPIN (-3350 5275) BN 15
J 0
(-3362 5283);
DISPLAY 0.489362 (-3362 5283);
PAINT GREEN (-3362 5283);
FORCEPROP 2 LAST CDS_LIB mstr_standard
J 0
(-3300 5275);
DISPLAY 0.723404 (-3300 5275);
PAINT MONO (-3300 5275);
DISPLAY INVISIBLE (-3300 5275);
FORCEPROP 1 LAST BODY_TYPE PLUMBING
J 0
(-3300 5325);
DISPLAY 0.872340 (-3300 5325);
PAINT GREEN (-3300 5325);
DISPLAY INVISIBLE (-3300 5325);
FORCEPROP 1 LAST HDL_TAP TRUE
J 0
(-2975 5150);
DISPLAY 0.872340 (-2975 5150);
DISPLAY INVISIBLE (-2975 5150);
FORCEPROP 1 LAST PATH I185
J 0
(-3302 5275);
DISPLAY 0.872340 (-3302 5275);
PAINT GREEN (-3302 5275);
DISPLAY INVISIBLE (-3302 5275);
FORCEADD TAP..1
(-3300 5125);
FORCEPROP 3 LASTPIN (-3350 5125) SIG_NAME M_A_CPU1_SA_DQ<17>
J 0
(-3340 5135);
DISPLAY 0.659574 (-3340 5135);
PAINT MONO (-3340 5135);
DISPLAY INVISIBLE (-3340 5135);
FORCEPROP 1 LASTPIN (-3350 5125) BN 17
J 0
(-3362 5133);
DISPLAY 0.489362 (-3362 5133);
PAINT GREEN (-3362 5133);
FORCEPROP 2 LAST CDS_LIB mstr_standard
J 0
(-3300 5125);
DISPLAY 0.723404 (-3300 5125);
PAINT MONO (-3300 5125);
DISPLAY INVISIBLE (-3300 5125);
FORCEPROP 1 LAST BODY_TYPE PLUMBING
J 0
(-3300 5175);
DISPLAY 0.872340 (-3300 5175);
PAINT GREEN (-3300 5175);
DISPLAY INVISIBLE (-3300 5175);
FORCEPROP 1 LAST HDL_TAP TRUE
J 0
(-2975 5000);
DISPLAY 0.872340 (-2975 5000);
DISPLAY INVISIBLE (-2975 5000);
FORCEPROP 1 LAST PATH I186
J 0
(-3302 5125);
DISPLAY 0.872340 (-3302 5125);
PAINT GREEN (-3302 5125);
DISPLAY INVISIBLE (-3302 5125);
FORCEADD TAP..1
(-3300 5175);
FORCEPROP 3 LASTPIN (-3350 5175) SIG_NAME M_A_CPU1_SA_DQ<16>
J 0
(-3340 5185);
DISPLAY 0.659574 (-3340 5185);
PAINT MONO (-3340 5185);
DISPLAY INVISIBLE (-3340 5185);
FORCEPROP 1 LASTPIN (-3350 5175) BN 16
J 0
(-3362 5183);
DISPLAY 0.489362 (-3362 5183);
PAINT GREEN (-3362 5183);
FORCEPROP 2 LAST CDS_LIB mstr_standard
J 0
(-3300 5175);
DISPLAY 0.723404 (-3300 5175);
PAINT MONO (-3300 5175);
DISPLAY INVISIBLE (-3300 5175);
FORCEPROP 1 LAST BODY_TYPE PLUMBING
J 0
(-3300 5225);
DISPLAY 0.872340 (-3300 5225);
PAINT GREEN (-3300 5225);
DISPLAY INVISIBLE (-3300 5225);
FORCEPROP 1 LAST HDL_TAP TRUE
J 0
(-2975 5050);
DISPLAY 0.872340 (-2975 5050);
DISPLAY INVISIBLE (-2975 5050);
FORCEPROP 1 LAST PATH I187
J 0
(-3302 5175);
DISPLAY 0.872340 (-3302 5175);
PAINT GREEN (-3302 5175);
DISPLAY INVISIBLE (-3302 5175);
FORCEADD TAP..1
(-3300 5075);
FORCEPROP 3 LASTPIN (-3350 5075) SIG_NAME M_A_CPU1_SA_DQ<18>
J 0
(-3340 5085);
DISPLAY 0.659574 (-3340 5085);
PAINT MONO (-3340 5085);
DISPLAY INVISIBLE (-3340 5085);
FORCEPROP 1 LASTPIN (-3350 5075) BN 18
J 0
(-3362 5083);
DISPLAY 0.489362 (-3362 5083);
PAINT GREEN (-3362 5083);
FORCEPROP 2 LAST CDS_LIB mstr_standard
J 0
(-3300 5075);
DISPLAY 0.723404 (-3300 5075);
PAINT MONO (-3300 5075);
DISPLAY INVISIBLE (-3300 5075);
FORCEPROP 1 LAST BODY_TYPE PLUMBING
J 0
(-3300 5125);
DISPLAY 0.872340 (-3300 5125);
PAINT GREEN (-3300 5125);
DISPLAY INVISIBLE (-3300 5125);
FORCEPROP 1 LAST HDL_TAP TRUE
J 0
(-2975 4950);
DISPLAY 0.872340 (-2975 4950);
DISPLAY INVISIBLE (-2975 4950);
FORCEPROP 1 LAST PATH I188
J 0
(-3302 5075);
DISPLAY 0.872340 (-3302 5075);
PAINT GREEN (-3302 5075);
DISPLAY INVISIBLE (-3302 5075);
FORCEADD TAP..1
(-3300 5025);
FORCEPROP 3 LASTPIN (-3350 5025) SIG_NAME M_A_CPU1_SA_DQ<19>
J 0
(-3340 5035);
DISPLAY 0.659574 (-3340 5035);
PAINT MONO (-3340 5035);
DISPLAY INVISIBLE (-3340 5035);
FORCEPROP 1 LASTPIN (-3350 5025) BN 19
J 0
(-3362 5033);
DISPLAY 0.489362 (-3362 5033);
PAINT GREEN (-3362 5033);
FORCEPROP 2 LAST CDS_LIB mstr_standard
J 0
(-3300 5025);
DISPLAY 0.723404 (-3300 5025);
PAINT MONO (-3300 5025);
DISPLAY INVISIBLE (-3300 5025);
FORCEPROP 1 LAST BODY_TYPE PLUMBING
J 0
(-3300 5075);
DISPLAY 0.872340 (-3300 5075);
PAINT GREEN (-3300 5075);
DISPLAY INVISIBLE (-3300 5075);
FORCEPROP 1 LAST HDL_TAP TRUE
J 0
(-2975 4900);
DISPLAY 0.872340 (-2975 4900);
DISPLAY INVISIBLE (-2975 4900);
FORCEPROP 1 LAST PATH I189
J 0
(-3302 5025);
DISPLAY 0.872340 (-3302 5025);
PAINT GREEN (-3302 5025);
DISPLAY INVISIBLE (-3302 5025);
FORCEADD TAP..1
(-3300 4975);
FORCEPROP 3 LASTPIN (-3350 4975) SIG_NAME M_A_CPU1_SA_DQ<20>
J 0
(-3340 4985);
DISPLAY 0.659574 (-3340 4985);
PAINT MONO (-3340 4985);
DISPLAY INVISIBLE (-3340 4985);
FORCEPROP 1 LASTPIN (-3350 4975) BN 20
J 0
(-3362 4983);
DISPLAY 0.489362 (-3362 4983);
PAINT GREEN (-3362 4983);
FORCEPROP 2 LAST CDS_LIB mstr_standard
J 0
(-3300 4975);
DISPLAY 0.723404 (-3300 4975);
PAINT MONO (-3300 4975);
DISPLAY INVISIBLE (-3300 4975);
FORCEPROP 1 LAST BODY_TYPE PLUMBING
J 0
(-3300 5025);
DISPLAY 0.872340 (-3300 5025);
PAINT GREEN (-3300 5025);
DISPLAY INVISIBLE (-3300 5025);
FORCEPROP 1 LAST HDL_TAP TRUE
J 0
(-2975 4850);
DISPLAY 0.872340 (-2975 4850);
DISPLAY INVISIBLE (-2975 4850);
FORCEPROP 1 LAST PATH I190
J 0
(-3302 4975);
DISPLAY 0.872340 (-3302 4975);
PAINT GREEN (-3302 4975);
DISPLAY INVISIBLE (-3302 4975);
FORCEADD TAP..1
(-3300 4875);
FORCEPROP 3 LASTPIN (-3350 4875) SIG_NAME M_A_CPU1_SA_DQ<22>
J 0
(-3340 4885);
DISPLAY 0.659574 (-3340 4885);
PAINT MONO (-3340 4885);
DISPLAY INVISIBLE (-3340 4885);
FORCEPROP 1 LASTPIN (-3350 4875) BN 22
J 0
(-3362 4883);
DISPLAY 0.489362 (-3362 4883);
PAINT GREEN (-3362 4883);
FORCEPROP 2 LAST CDS_LIB mstr_standard
J 0
(-3300 4875);
DISPLAY 0.723404 (-3300 4875);
PAINT MONO (-3300 4875);
DISPLAY INVISIBLE (-3300 4875);
FORCEPROP 1 LAST BODY_TYPE PLUMBING
J 0
(-3300 4925);
DISPLAY 0.872340 (-3300 4925);
PAINT GREEN (-3300 4925);
DISPLAY INVISIBLE (-3300 4925);
FORCEPROP 1 LAST HDL_TAP TRUE
J 0
(-2975 4750);
DISPLAY 0.872340 (-2975 4750);
DISPLAY INVISIBLE (-2975 4750);
FORCEPROP 1 LAST PATH I191
J 0
(-3302 4875);
DISPLAY 0.872340 (-3302 4875);
PAINT GREEN (-3302 4875);
DISPLAY INVISIBLE (-3302 4875);
FORCEADD TAP..1
(-3300 4925);
FORCEPROP 3 LASTPIN (-3350 4925) SIG_NAME M_A_CPU1_SA_DQ<21>
J 0
(-3340 4935);
DISPLAY 0.659574 (-3340 4935);
PAINT MONO (-3340 4935);
DISPLAY INVISIBLE (-3340 4935);
FORCEPROP 1 LASTPIN (-3350 4925) BN 21
J 0
(-3362 4933);
DISPLAY 0.489362 (-3362 4933);
PAINT GREEN (-3362 4933);
FORCEPROP 2 LAST CDS_LIB mstr_standard
J 0
(-3300 4925);
DISPLAY 0.723404 (-3300 4925);
PAINT MONO (-3300 4925);
DISPLAY INVISIBLE (-3300 4925);
FORCEPROP 1 LAST BODY_TYPE PLUMBING
J 0
(-3300 4975);
DISPLAY 0.872340 (-3300 4975);
PAINT GREEN (-3300 4975);
DISPLAY INVISIBLE (-3300 4975);
FORCEPROP 1 LAST HDL_TAP TRUE
J 0
(-2975 4800);
DISPLAY 0.872340 (-2975 4800);
DISPLAY INVISIBLE (-2975 4800);
FORCEPROP 1 LAST PATH I192
J 0
(-3302 4925);
DISPLAY 0.872340 (-3302 4925);
PAINT GREEN (-3302 4925);
DISPLAY INVISIBLE (-3302 4925);
FORCEADD TAP..1
(-3300 4825);
FORCEPROP 3 LASTPIN (-3350 4825) SIG_NAME M_A_CPU1_SA_DQ<23>
J 0
(-3340 4835);
DISPLAY 0.659574 (-3340 4835);
PAINT MONO (-3340 4835);
DISPLAY INVISIBLE (-3340 4835);
FORCEPROP 1 LASTPIN (-3350 4825) BN 23
J 0
(-3362 4833);
DISPLAY 0.489362 (-3362 4833);
PAINT GREEN (-3362 4833);
FORCEPROP 2 LAST CDS_LIB mstr_standard
J 0
(-3300 4825);
DISPLAY 0.723404 (-3300 4825);
PAINT MONO (-3300 4825);
DISPLAY INVISIBLE (-3300 4825);
FORCEPROP 1 LAST BODY_TYPE PLUMBING
J 0
(-3300 4875);
DISPLAY 0.872340 (-3300 4875);
PAINT GREEN (-3300 4875);
DISPLAY INVISIBLE (-3300 4875);
FORCEPROP 1 LAST HDL_TAP TRUE
J 0
(-2975 4700);
DISPLAY 0.872340 (-2975 4700);
DISPLAY INVISIBLE (-2975 4700);
FORCEPROP 1 LAST PATH I193
J 0
(-3302 4825);
DISPLAY 0.872340 (-3302 4825);
PAINT GREEN (-3302 4825);
DISPLAY INVISIBLE (-3302 4825);
FORCEADD TAP..1
(-3300 4675);
FORCEPROP 3 LASTPIN (-3350 4675) SIG_NAME M_A_CPU1_SA_DQ<25>
J 0
(-3340 4685);
DISPLAY 0.659574 (-3340 4685);
PAINT MONO (-3340 4685);
DISPLAY INVISIBLE (-3340 4685);
FORCEPROP 1 LASTPIN (-3350 4675) BN 25
J 0
(-3362 4683);
DISPLAY 0.489362 (-3362 4683);
PAINT GREEN (-3362 4683);
FORCEPROP 2 LAST CDS_LIB mstr_standard
J 0
(-3300 4675);
DISPLAY 0.723404 (-3300 4675);
PAINT MONO (-3300 4675);
DISPLAY INVISIBLE (-3300 4675);
FORCEPROP 1 LAST BODY_TYPE PLUMBING
J 0
(-3300 4725);
DISPLAY 0.872340 (-3300 4725);
PAINT GREEN (-3300 4725);
DISPLAY INVISIBLE (-3300 4725);
FORCEPROP 1 LAST HDL_TAP TRUE
J 0
(-2975 4550);
DISPLAY 0.872340 (-2975 4550);
DISPLAY INVISIBLE (-2975 4550);
FORCEPROP 1 LAST PATH I194
J 0
(-3302 4675);
DISPLAY 0.872340 (-3302 4675);
PAINT GREEN (-3302 4675);
DISPLAY INVISIBLE (-3302 4675);
FORCEADD TAP..1
(-3300 4725);
FORCEPROP 3 LASTPIN (-3350 4725) SIG_NAME M_A_CPU1_SA_DQ<24>
J 0
(-3340 4735);
DISPLAY 0.659574 (-3340 4735);
PAINT MONO (-3340 4735);
DISPLAY INVISIBLE (-3340 4735);
FORCEPROP 1 LASTPIN (-3350 4725) BN 24
J 0
(-3362 4733);
DISPLAY 0.489362 (-3362 4733);
PAINT GREEN (-3362 4733);
FORCEPROP 2 LAST CDS_LIB mstr_standard
J 0
(-3300 4725);
DISPLAY 0.723404 (-3300 4725);
PAINT MONO (-3300 4725);
DISPLAY INVISIBLE (-3300 4725);
FORCEPROP 1 LAST BODY_TYPE PLUMBING
J 0
(-3300 4775);
DISPLAY 0.872340 (-3300 4775);
PAINT GREEN (-3300 4775);
DISPLAY INVISIBLE (-3300 4775);
FORCEPROP 1 LAST HDL_TAP TRUE
J 0
(-2975 4600);
DISPLAY 0.872340 (-2975 4600);
DISPLAY INVISIBLE (-2975 4600);
FORCEPROP 1 LAST PATH I195
J 0
(-3302 4725);
DISPLAY 0.872340 (-3302 4725);
PAINT GREEN (-3302 4725);
DISPLAY INVISIBLE (-3302 4725);
FORCEADD TAP..1
(-3300 4625);
FORCEPROP 3 LASTPIN (-3350 4625) SIG_NAME M_A_CPU1_SA_DQ<26>
J 0
(-3340 4635);
DISPLAY 0.659574 (-3340 4635);
PAINT MONO (-3340 4635);
DISPLAY INVISIBLE (-3340 4635);
FORCEPROP 1 LASTPIN (-3350 4625) BN 26
J 0
(-3362 4633);
DISPLAY 0.489362 (-3362 4633);
PAINT GREEN (-3362 4633);
FORCEPROP 2 LAST CDS_LIB mstr_standard
J 0
(-3300 4625);
DISPLAY 0.723404 (-3300 4625);
PAINT MONO (-3300 4625);
DISPLAY INVISIBLE (-3300 4625);
FORCEPROP 1 LAST BODY_TYPE PLUMBING
J 0
(-3300 4675);
DISPLAY 0.872340 (-3300 4675);
PAINT GREEN (-3300 4675);
DISPLAY INVISIBLE (-3300 4675);
FORCEPROP 1 LAST HDL_TAP TRUE
J 0
(-2975 4500);
DISPLAY 0.872340 (-2975 4500);
DISPLAY INVISIBLE (-2975 4500);
FORCEPROP 1 LAST PATH I196
J 0
(-3302 4625);
DISPLAY 0.872340 (-3302 4625);
PAINT GREEN (-3302 4625);
DISPLAY INVISIBLE (-3302 4625);
FORCEADD TAP..1
(-3300 4575);
FORCEPROP 3 LASTPIN (-3350 4575) SIG_NAME M_A_CPU1_SA_DQ<27>
J 0
(-3340 4585);
DISPLAY 0.659574 (-3340 4585);
PAINT MONO (-3340 4585);
DISPLAY INVISIBLE (-3340 4585);
FORCEPROP 1 LASTPIN (-3350 4575) BN 27
J 0
(-3362 4583);
DISPLAY 0.489362 (-3362 4583);
PAINT GREEN (-3362 4583);
FORCEPROP 2 LAST CDS_LIB mstr_standard
J 0
(-3300 4575);
DISPLAY 0.723404 (-3300 4575);
PAINT MONO (-3300 4575);
DISPLAY INVISIBLE (-3300 4575);
FORCEPROP 1 LAST BODY_TYPE PLUMBING
J 0
(-3300 4625);
DISPLAY 0.872340 (-3300 4625);
PAINT GREEN (-3300 4625);
DISPLAY INVISIBLE (-3300 4625);
FORCEPROP 1 LAST HDL_TAP TRUE
J 0
(-2975 4450);
DISPLAY 0.872340 (-2975 4450);
DISPLAY INVISIBLE (-2975 4450);
FORCEPROP 1 LAST PATH I197
J 0
(-3302 4575);
DISPLAY 0.872340 (-3302 4575);
PAINT GREEN (-3302 4575);
DISPLAY INVISIBLE (-3302 4575);
FORCEADD TAP..1
(-3300 4525);
FORCEPROP 3 LASTPIN (-3350 4525) SIG_NAME M_A_CPU1_SA_DQ<28>
J 0
(-3340 4535);
DISPLAY 0.659574 (-3340 4535);
PAINT MONO (-3340 4535);
DISPLAY INVISIBLE (-3340 4535);
FORCEPROP 1 LASTPIN (-3350 4525) BN 28
J 0
(-3362 4533);
DISPLAY 0.489362 (-3362 4533);
PAINT GREEN (-3362 4533);
FORCEPROP 2 LAST CDS_LIB mstr_standard
J 0
(-3300 4525);
DISPLAY 0.723404 (-3300 4525);
PAINT MONO (-3300 4525);
DISPLAY INVISIBLE (-3300 4525);
FORCEPROP 1 LAST BODY_TYPE PLUMBING
J 0
(-3300 4575);
DISPLAY 0.872340 (-3300 4575);
PAINT GREEN (-3300 4575);
DISPLAY INVISIBLE (-3300 4575);
FORCEPROP 1 LAST HDL_TAP TRUE
J 0
(-2975 4400);
DISPLAY 0.872340 (-2975 4400);
DISPLAY INVISIBLE (-2975 4400);
FORCEPROP 1 LAST PATH I198
J 0
(-3302 4525);
DISPLAY 0.872340 (-3302 4525);
PAINT GREEN (-3302 4525);
DISPLAY INVISIBLE (-3302 4525);
FORCEADD TAP..1
(-3300 4475);
FORCEPROP 3 LASTPIN (-3350 4475) SIG_NAME M_A_CPU1_SA_DQ<29>
J 0
(-3340 4485);
DISPLAY 0.659574 (-3340 4485);
PAINT MONO (-3340 4485);
DISPLAY INVISIBLE (-3340 4485);
FORCEPROP 1 LASTPIN (-3350 4475) BN 29
J 0
(-3362 4483);
DISPLAY 0.489362 (-3362 4483);
PAINT GREEN (-3362 4483);
FORCEPROP 2 LAST CDS_LIB mstr_standard
J 0
(-3300 4475);
DISPLAY 0.723404 (-3300 4475);
PAINT MONO (-3300 4475);
DISPLAY INVISIBLE (-3300 4475);
FORCEPROP 1 LAST BODY_TYPE PLUMBING
J 0
(-3300 4525);
DISPLAY 0.872340 (-3300 4525);
PAINT GREEN (-3300 4525);
DISPLAY INVISIBLE (-3300 4525);
FORCEPROP 1 LAST HDL_TAP TRUE
J 0
(-2975 4350);
DISPLAY 0.872340 (-2975 4350);
DISPLAY INVISIBLE (-2975 4350);
FORCEPROP 1 LAST PATH I199
J 0
(-3302 4475);
DISPLAY 0.872340 (-3302 4475);
PAINT GREEN (-3302 4475);
DISPLAY INVISIBLE (-3302 4475);
FORCEADD TAP..1
(-3300 4425);
FORCEPROP 3 LASTPIN (-3350 4425) SIG_NAME M_A_CPU1_SA_DQ<30>
J 0
(-3340 4435);
DISPLAY 0.659574 (-3340 4435);
PAINT MONO (-3340 4435);
DISPLAY INVISIBLE (-3340 4435);
FORCEPROP 1 LASTPIN (-3350 4425) BN 30
J 0
(-3362 4433);
DISPLAY 0.489362 (-3362 4433);
PAINT GREEN (-3362 4433);
FORCEPROP 2 LAST CDS_LIB mstr_standard
J 0
(-3300 4425);
DISPLAY 0.723404 (-3300 4425);
PAINT MONO (-3300 4425);
DISPLAY INVISIBLE (-3300 4425);
FORCEPROP 1 LAST BODY_TYPE PLUMBING
J 0
(-3300 4475);
DISPLAY 0.872340 (-3300 4475);
PAINT GREEN (-3300 4475);
DISPLAY INVISIBLE (-3300 4475);
FORCEPROP 1 LAST HDL_TAP TRUE
J 0
(-2975 4300);
DISPLAY 0.872340 (-2975 4300);
DISPLAY INVISIBLE (-2975 4300);
FORCEPROP 1 LAST PATH I200
J 0
(-3302 4425);
DISPLAY 0.872340 (-3302 4425);
PAINT GREEN (-3302 4425);
DISPLAY INVISIBLE (-3302 4425);
FORCEADD TAP..1
(-3300 4375);
FORCEPROP 3 LASTPIN (-3350 4375) SIG_NAME M_A_CPU1_SA_DQ<31>
J 0
(-3340 4385);
DISPLAY 0.659574 (-3340 4385);
PAINT MONO (-3340 4385);
DISPLAY INVISIBLE (-3340 4385);
FORCEPROP 1 LASTPIN (-3350 4375) BN 31
J 0
(-3362 4383);
DISPLAY 0.489362 (-3362 4383);
PAINT GREEN (-3362 4383);
FORCEPROP 2 LAST CDS_LIB mstr_standard
J 0
(-3300 4375);
DISPLAY 0.723404 (-3300 4375);
PAINT MONO (-3300 4375);
DISPLAY INVISIBLE (-3300 4375);
FORCEPROP 1 LAST BODY_TYPE PLUMBING
J 0
(-3300 4425);
DISPLAY 0.872340 (-3300 4425);
PAINT GREEN (-3300 4425);
DISPLAY INVISIBLE (-3300 4425);
FORCEPROP 1 LAST HDL_TAP TRUE
J 0
(-2975 4250);
DISPLAY 0.872340 (-2975 4250);
DISPLAY INVISIBLE (-2975 4250);
FORCEPROP 1 LAST PATH I201
J 0
(-3302 4375);
DISPLAY 0.872340 (-3302 4375);
PAINT GREEN (-3302 4375);
DISPLAY INVISIBLE (-3302 4375);
FORCEADD TAP..1
(-3300 4225);
FORCEPROP 3 LASTPIN (-3350 4225) SIG_NAME M_A_CPU1_SB_DQ<1>
J 0
(-3340 4235);
DISPLAY 0.659574 (-3340 4235);
PAINT MONO (-3340 4235);
DISPLAY INVISIBLE (-3340 4235);
FORCEPROP 1 LASTPIN (-3350 4225) BN 1
J 0
(-3362 4233);
DISPLAY 0.489362 (-3362 4233);
PAINT GREEN (-3362 4233);
FORCEPROP 2 LAST CDS_LIB mstr_standard
J 0
(-3300 4225);
DISPLAY 0.723404 (-3300 4225);
PAINT MONO (-3300 4225);
DISPLAY INVISIBLE (-3300 4225);
FORCEPROP 1 LAST BODY_TYPE PLUMBING
J 0
(-3300 4275);
DISPLAY 0.872340 (-3300 4275);
PAINT GREEN (-3300 4275);
DISPLAY INVISIBLE (-3300 4275);
FORCEPROP 1 LAST HDL_TAP TRUE
J 0
(-2975 4100);
DISPLAY 0.872340 (-2975 4100);
DISPLAY INVISIBLE (-2975 4100);
FORCEPROP 1 LAST PATH I202
J 0
(-3302 4225);
DISPLAY 0.872340 (-3302 4225);
PAINT GREEN (-3302 4225);
DISPLAY INVISIBLE (-3302 4225);
FORCEADD TAP..1
(-3300 4275);
FORCEPROP 3 LASTPIN (-3350 4275) SIG_NAME M_A_CPU1_SB_DQ<0>
J 0
(-3340 4285);
DISPLAY 0.659574 (-3340 4285);
PAINT MONO (-3340 4285);
DISPLAY INVISIBLE (-3340 4285);
FORCEPROP 1 LASTPIN (-3350 4275) BN 0
J 0
(-3362 4283);
DISPLAY 0.489362 (-3362 4283);
PAINT GREEN (-3362 4283);
FORCEPROP 2 LAST CDS_LIB mstr_standard
J 0
(-3300 4275);
DISPLAY 0.723404 (-3300 4275);
PAINT MONO (-3300 4275);
DISPLAY INVISIBLE (-3300 4275);
FORCEPROP 1 LAST BODY_TYPE PLUMBING
J 0
(-3300 4325);
DISPLAY 0.872340 (-3300 4325);
PAINT GREEN (-3300 4325);
DISPLAY INVISIBLE (-3300 4325);
FORCEPROP 1 LAST HDL_TAP TRUE
J 0
(-2975 4150);
DISPLAY 0.872340 (-2975 4150);
DISPLAY INVISIBLE (-2975 4150);
FORCEPROP 1 LAST PATH I203
J 0
(-3302 4275);
DISPLAY 0.872340 (-3302 4275);
PAINT GREEN (-3302 4275);
DISPLAY INVISIBLE (-3302 4275);
FORCEADD TAP..1
(-3300 4125);
FORCEPROP 3 LASTPIN (-3350 4125) SIG_NAME M_A_CPU1_SB_DQ<3>
J 0
(-3340 4135);
DISPLAY 0.659574 (-3340 4135);
PAINT MONO (-3340 4135);
DISPLAY INVISIBLE (-3340 4135);
FORCEPROP 1 LASTPIN (-3350 4125) BN 3
J 0
(-3362 4133);
DISPLAY 0.489362 (-3362 4133);
PAINT GREEN (-3362 4133);
FORCEPROP 2 LAST CDS_LIB mstr_standard
J 0
(-3300 4125);
DISPLAY 0.723404 (-3300 4125);
PAINT MONO (-3300 4125);
DISPLAY INVISIBLE (-3300 4125);
FORCEPROP 1 LAST BODY_TYPE PLUMBING
J 0
(-3300 4175);
DISPLAY 0.872340 (-3300 4175);
PAINT GREEN (-3300 4175);
DISPLAY INVISIBLE (-3300 4175);
FORCEPROP 1 LAST HDL_TAP TRUE
J 0
(-2975 4000);
DISPLAY 0.872340 (-2975 4000);
DISPLAY INVISIBLE (-2975 4000);
FORCEPROP 1 LAST PATH I204
J 0
(-3302 4125);
DISPLAY 0.872340 (-3302 4125);
PAINT GREEN (-3302 4125);
DISPLAY INVISIBLE (-3302 4125);
FORCEADD TAP..1
(-3300 4175);
FORCEPROP 3 LASTPIN (-3350 4175) SIG_NAME M_A_CPU1_SB_DQ<2>
J 0
(-3340 4185);
DISPLAY 0.659574 (-3340 4185);
PAINT MONO (-3340 4185);
DISPLAY INVISIBLE (-3340 4185);
FORCEPROP 1 LASTPIN (-3350 4175) BN 2
J 0
(-3362 4183);
DISPLAY 0.489362 (-3362 4183);
PAINT GREEN (-3362 4183);
FORCEPROP 2 LAST CDS_LIB mstr_standard
J 0
(-3300 4175);
DISPLAY 0.723404 (-3300 4175);
PAINT MONO (-3300 4175);
DISPLAY INVISIBLE (-3300 4175);
FORCEPROP 1 LAST BODY_TYPE PLUMBING
J 0
(-3300 4225);
DISPLAY 0.872340 (-3300 4225);
PAINT GREEN (-3300 4225);
DISPLAY INVISIBLE (-3300 4225);
FORCEPROP 1 LAST HDL_TAP TRUE
J 0
(-2975 4050);
DISPLAY 0.872340 (-2975 4050);
DISPLAY INVISIBLE (-2975 4050);
FORCEPROP 1 LAST PATH I205
J 0
(-3302 4175);
DISPLAY 0.872340 (-3302 4175);
PAINT GREEN (-3302 4175);
DISPLAY INVISIBLE (-3302 4175);
FORCEADD OFFPAGE..6
R 2
(-2700 2525);
FORCEPROP 2 LAST $XR0 98 
J 0
(-2486 2525);
DISPLAY 0.638298 (-2486 2525);
PAINT MONO (-2486 2525);
FORCEPROP 2 LAST CDS_LIB mstr_standard
J 2
(-2700 2525);
DISPLAY 0.723404 (-2700 2525);
PAINT MONO (-2700 2525);
DISPLAY INVISIBLE (-2700 2525);
FORCEPROP 1 LAST OFFPAGE TRUE
J 2
(-3025 2400);
DISPLAY 0.872340 (-3025 2400);
PAINT GREEN (-3025 2400);
DISPLAY INVISIBLE (-3025 2400);
FORCEPROP 1 LAST COMMENT_BODY TRUE
J 2
(-2800 2450);
DISPLAY 0.872340 (-2800 2450);
PAINT GREEN (-2800 2450);
DISPLAY INVISIBLE (-2800 2450);
FORCEPROP 2 LAST PATH I206
J 0
(-2475 2575);
DISPLAY 1.021277 (-2475 2575);
DISPLAY INVISIBLE (-2475 2575);
FORCEADD TAP..1
(-3300 4075);
FORCEPROP 3 LASTPIN (-3350 4075) SIG_NAME M_A_CPU1_SB_DQ<4>
J 0
(-3340 4085);
DISPLAY 0.659574 (-3340 4085);
PAINT MONO (-3340 4085);
DISPLAY INVISIBLE (-3340 4085);
FORCEPROP 1 LASTPIN (-3350 4075) BN 4
J 0
(-3362 4083);
DISPLAY 0.489362 (-3362 4083);
PAINT GREEN (-3362 4083);
FORCEPROP 2 LAST CDS_LIB mstr_standard
J 0
(-3300 4075);
DISPLAY 0.723404 (-3300 4075);
PAINT MONO (-3300 4075);
DISPLAY INVISIBLE (-3300 4075);
FORCEPROP 1 LAST BODY_TYPE PLUMBING
J 0
(-3300 4125);
DISPLAY 0.872340 (-3300 4125);
PAINT GREEN (-3300 4125);
DISPLAY INVISIBLE (-3300 4125);
FORCEPROP 1 LAST HDL_TAP TRUE
J 0
(-2975 3950);
DISPLAY 0.872340 (-2975 3950);
DISPLAY INVISIBLE (-2975 3950);
FORCEPROP 1 LAST PATH I207
J 0
(-3302 4075);
DISPLAY 0.872340 (-3302 4075);
PAINT GREEN (-3302 4075);
DISPLAY INVISIBLE (-3302 4075);
FORCEADD TAP..1
(-3300 3975);
FORCEPROP 3 LASTPIN (-3350 3975) SIG_NAME M_A_CPU1_SB_DQ<6>
J 0
(-3340 3985);
DISPLAY 0.659574 (-3340 3985);
PAINT MONO (-3340 3985);
DISPLAY INVISIBLE (-3340 3985);
FORCEPROP 1 LASTPIN (-3350 3975) BN 6
J 0
(-3362 3983);
DISPLAY 0.489362 (-3362 3983);
PAINT GREEN (-3362 3983);
FORCEPROP 2 LAST CDS_LIB mstr_standard
J 0
(-3300 3975);
DISPLAY 0.723404 (-3300 3975);
PAINT MONO (-3300 3975);
DISPLAY INVISIBLE (-3300 3975);
FORCEPROP 1 LAST BODY_TYPE PLUMBING
J 0
(-3300 4025);
DISPLAY 0.872340 (-3300 4025);
PAINT GREEN (-3300 4025);
DISPLAY INVISIBLE (-3300 4025);
FORCEPROP 1 LAST HDL_TAP TRUE
J 0
(-2975 3850);
DISPLAY 0.872340 (-2975 3850);
DISPLAY INVISIBLE (-2975 3850);
FORCEPROP 1 LAST PATH I208
J 0
(-3302 3975);
DISPLAY 0.872340 (-3302 3975);
PAINT GREEN (-3302 3975);
DISPLAY INVISIBLE (-3302 3975);
FORCEADD TAP..1
(-3300 4025);
FORCEPROP 3 LASTPIN (-3350 4025) SIG_NAME M_A_CPU1_SB_DQ<5>
J 0
(-3340 4035);
DISPLAY 0.659574 (-3340 4035);
PAINT MONO (-3340 4035);
DISPLAY INVISIBLE (-3340 4035);
FORCEPROP 1 LASTPIN (-3350 4025) BN 5
J 0
(-3362 4033);
DISPLAY 0.489362 (-3362 4033);
PAINT GREEN (-3362 4033);
FORCEPROP 2 LAST CDS_LIB mstr_standard
J 0
(-3300 4025);
DISPLAY 0.723404 (-3300 4025);
PAINT MONO (-3300 4025);
DISPLAY INVISIBLE (-3300 4025);
FORCEPROP 1 LAST BODY_TYPE PLUMBING
J 0
(-3300 4075);
DISPLAY 0.872340 (-3300 4075);
PAINT GREEN (-3300 4075);
DISPLAY INVISIBLE (-3300 4075);
FORCEPROP 1 LAST HDL_TAP TRUE
J 0
(-2975 3900);
DISPLAY 0.872340 (-2975 3900);
DISPLAY INVISIBLE (-2975 3900);
FORCEPROP 1 LAST PATH I209
J 0
(-3302 4025);
DISPLAY 0.872340 (-3302 4025);
PAINT GREEN (-3302 4025);
DISPLAY INVISIBLE (-3302 4025);
FORCEADD TAP..1
(-3300 3925);
FORCEPROP 3 LASTPIN (-3350 3925) SIG_NAME M_A_CPU1_SB_DQ<7>
J 0
(-3340 3935);
DISPLAY 0.659574 (-3340 3935);
PAINT MONO (-3340 3935);
DISPLAY INVISIBLE (-3340 3935);
FORCEPROP 1 LASTPIN (-3350 3925) BN 7
J 0
(-3362 3933);
DISPLAY 0.489362 (-3362 3933);
PAINT GREEN (-3362 3933);
FORCEPROP 2 LAST CDS_LIB mstr_standard
J 0
(-3300 3925);
DISPLAY 0.723404 (-3300 3925);
PAINT MONO (-3300 3925);
DISPLAY INVISIBLE (-3300 3925);
FORCEPROP 1 LAST BODY_TYPE PLUMBING
J 0
(-3300 3975);
DISPLAY 0.872340 (-3300 3975);
PAINT GREEN (-3300 3975);
DISPLAY INVISIBLE (-3300 3975);
FORCEPROP 1 LAST HDL_TAP TRUE
J 0
(-2975 3800);
DISPLAY 0.872340 (-2975 3800);
DISPLAY INVISIBLE (-2975 3800);
FORCEPROP 1 LAST PATH I210
J 0
(-3302 3925);
DISPLAY 0.872340 (-3302 3925);
PAINT GREEN (-3302 3925);
DISPLAY INVISIBLE (-3302 3925);
FORCEADD TAP..1
(-3300 3825);
FORCEPROP 3 LASTPIN (-3350 3825) SIG_NAME M_A_CPU1_SB_DQ<8>
J 0
(-3340 3835);
DISPLAY 0.659574 (-3340 3835);
PAINT MONO (-3340 3835);
DISPLAY INVISIBLE (-3340 3835);
FORCEPROP 1 LASTPIN (-3350 3825) BN 8
J 0
(-3362 3833);
DISPLAY 0.489362 (-3362 3833);
PAINT GREEN (-3362 3833);
FORCEPROP 2 LAST CDS_LIB mstr_standard
J 0
(-3300 3825);
DISPLAY 0.723404 (-3300 3825);
PAINT MONO (-3300 3825);
DISPLAY INVISIBLE (-3300 3825);
FORCEPROP 1 LAST BODY_TYPE PLUMBING
J 0
(-3300 3875);
DISPLAY 0.872340 (-3300 3875);
PAINT GREEN (-3300 3875);
DISPLAY INVISIBLE (-3300 3875);
FORCEPROP 1 LAST HDL_TAP TRUE
J 0
(-2975 3700);
DISPLAY 0.872340 (-2975 3700);
DISPLAY INVISIBLE (-2975 3700);
FORCEPROP 1 LAST PATH I211
J 0
(-3302 3825);
DISPLAY 0.872340 (-3302 3825);
PAINT GREEN (-3302 3825);
DISPLAY INVISIBLE (-3302 3825);
FORCEADD TAP..1
(-3300 3725);
FORCEPROP 3 LASTPIN (-3350 3725) SIG_NAME M_A_CPU1_SB_DQ<10>
J 0
(-3340 3735);
DISPLAY 0.659574 (-3340 3735);
PAINT MONO (-3340 3735);
DISPLAY INVISIBLE (-3340 3735);
FORCEPROP 1 LASTPIN (-3350 3725) BN 10
J 0
(-3362 3733);
DISPLAY 0.489362 (-3362 3733);
PAINT GREEN (-3362 3733);
FORCEPROP 2 LAST CDS_LIB mstr_standard
J 0
(-3300 3725);
DISPLAY 0.723404 (-3300 3725);
PAINT MONO (-3300 3725);
DISPLAY INVISIBLE (-3300 3725);
FORCEPROP 1 LAST BODY_TYPE PLUMBING
J 0
(-3300 3775);
DISPLAY 0.872340 (-3300 3775);
PAINT GREEN (-3300 3775);
DISPLAY INVISIBLE (-3300 3775);
FORCEPROP 1 LAST HDL_TAP TRUE
J 0
(-2975 3600);
DISPLAY 0.872340 (-2975 3600);
DISPLAY INVISIBLE (-2975 3600);
FORCEPROP 1 LAST PATH I212
J 0
(-3302 3725);
DISPLAY 0.872340 (-3302 3725);
PAINT GREEN (-3302 3725);
DISPLAY INVISIBLE (-3302 3725);
FORCEADD TAP..1
(-3300 3775);
FORCEPROP 3 LASTPIN (-3350 3775) SIG_NAME M_A_CPU1_SB_DQ<9>
J 0
(-3340 3785);
DISPLAY 0.659574 (-3340 3785);
PAINT MONO (-3340 3785);
DISPLAY INVISIBLE (-3340 3785);
FORCEPROP 1 LASTPIN (-3350 3775) BN 9
J 0
(-3362 3783);
DISPLAY 0.489362 (-3362 3783);
PAINT GREEN (-3362 3783);
FORCEPROP 2 LAST CDS_LIB mstr_standard
J 0
(-3300 3775);
DISPLAY 0.723404 (-3300 3775);
PAINT MONO (-3300 3775);
DISPLAY INVISIBLE (-3300 3775);
FORCEPROP 1 LAST BODY_TYPE PLUMBING
J 0
(-3300 3825);
DISPLAY 0.872340 (-3300 3825);
PAINT GREEN (-3300 3825);
DISPLAY INVISIBLE (-3300 3825);
FORCEPROP 1 LAST HDL_TAP TRUE
J 0
(-2975 3650);
DISPLAY 0.872340 (-2975 3650);
DISPLAY INVISIBLE (-2975 3650);
FORCEPROP 1 LAST PATH I213
J 0
(-3302 3775);
DISPLAY 0.872340 (-3302 3775);
PAINT GREEN (-3302 3775);
DISPLAY INVISIBLE (-3302 3775);
FORCEADD TAP..1
(-3300 3675);
FORCEPROP 3 LASTPIN (-3350 3675) SIG_NAME M_A_CPU1_SB_DQ<11>
J 0
(-3340 3685);
DISPLAY 0.659574 (-3340 3685);
PAINT MONO (-3340 3685);
DISPLAY INVISIBLE (-3340 3685);
FORCEPROP 1 LASTPIN (-3350 3675) BN 11
J 0
(-3362 3683);
DISPLAY 0.489362 (-3362 3683);
PAINT GREEN (-3362 3683);
FORCEPROP 2 LAST CDS_LIB mstr_standard
J 0
(-3300 3675);
DISPLAY 0.723404 (-3300 3675);
PAINT MONO (-3300 3675);
DISPLAY INVISIBLE (-3300 3675);
FORCEPROP 1 LAST BODY_TYPE PLUMBING
J 0
(-3300 3725);
DISPLAY 0.872340 (-3300 3725);
PAINT GREEN (-3300 3725);
DISPLAY INVISIBLE (-3300 3725);
FORCEPROP 1 LAST HDL_TAP TRUE
J 0
(-2975 3550);
DISPLAY 0.872340 (-2975 3550);
DISPLAY INVISIBLE (-2975 3550);
FORCEPROP 1 LAST PATH I214
J 0
(-3302 3675);
DISPLAY 0.872340 (-3302 3675);
PAINT GREEN (-3302 3675);
DISPLAY INVISIBLE (-3302 3675);
FORCEADD TAP..1
(-3300 3625);
FORCEPROP 3 LASTPIN (-3350 3625) SIG_NAME M_A_CPU1_SB_DQ<12>
J 0
(-3340 3635);
DISPLAY 0.659574 (-3340 3635);
PAINT MONO (-3340 3635);
DISPLAY INVISIBLE (-3340 3635);
FORCEPROP 1 LASTPIN (-3350 3625) BN 12
J 0
(-3362 3633);
DISPLAY 0.489362 (-3362 3633);
PAINT GREEN (-3362 3633);
FORCEPROP 2 LAST CDS_LIB mstr_standard
J 0
(-3300 3625);
DISPLAY 0.723404 (-3300 3625);
PAINT MONO (-3300 3625);
DISPLAY INVISIBLE (-3300 3625);
FORCEPROP 1 LAST BODY_TYPE PLUMBING
J 0
(-3300 3675);
DISPLAY 0.872340 (-3300 3675);
PAINT GREEN (-3300 3675);
DISPLAY INVISIBLE (-3300 3675);
FORCEPROP 1 LAST HDL_TAP TRUE
J 0
(-2975 3500);
DISPLAY 0.872340 (-2975 3500);
DISPLAY INVISIBLE (-2975 3500);
FORCEPROP 1 LAST PATH I215
J 0
(-3302 3625);
DISPLAY 0.872340 (-3302 3625);
PAINT GREEN (-3302 3625);
DISPLAY INVISIBLE (-3302 3625);
FORCEADD TAP..1
(-3300 3525);
FORCEPROP 3 LASTPIN (-3350 3525) SIG_NAME M_A_CPU1_SB_DQ<14>
J 0
(-3340 3535);
DISPLAY 0.659574 (-3340 3535);
PAINT MONO (-3340 3535);
DISPLAY INVISIBLE (-3340 3535);
FORCEPROP 1 LASTPIN (-3350 3525) BN 14
J 0
(-3362 3533);
DISPLAY 0.489362 (-3362 3533);
PAINT GREEN (-3362 3533);
FORCEPROP 2 LAST CDS_LIB mstr_standard
J 0
(-3300 3525);
DISPLAY 0.723404 (-3300 3525);
PAINT MONO (-3300 3525);
DISPLAY INVISIBLE (-3300 3525);
FORCEPROP 1 LAST BODY_TYPE PLUMBING
J 0
(-3300 3575);
DISPLAY 0.872340 (-3300 3575);
PAINT GREEN (-3300 3575);
DISPLAY INVISIBLE (-3300 3575);
FORCEPROP 1 LAST HDL_TAP TRUE
J 0
(-2975 3400);
DISPLAY 0.872340 (-2975 3400);
DISPLAY INVISIBLE (-2975 3400);
FORCEPROP 1 LAST PATH I216
J 0
(-3302 3525);
DISPLAY 0.872340 (-3302 3525);
PAINT GREEN (-3302 3525);
DISPLAY INVISIBLE (-3302 3525);
FORCEADD TAP..1
(-3300 3575);
FORCEPROP 3 LASTPIN (-3350 3575) SIG_NAME M_A_CPU1_SB_DQ<13>
J 0
(-3340 3585);
DISPLAY 0.659574 (-3340 3585);
PAINT MONO (-3340 3585);
DISPLAY INVISIBLE (-3340 3585);
FORCEPROP 1 LASTPIN (-3350 3575) BN 13
J 0
(-3362 3583);
DISPLAY 0.489362 (-3362 3583);
PAINT GREEN (-3362 3583);
FORCEPROP 2 LAST CDS_LIB mstr_standard
J 0
(-3300 3575);
DISPLAY 0.723404 (-3300 3575);
PAINT MONO (-3300 3575);
DISPLAY INVISIBLE (-3300 3575);
FORCEPROP 1 LAST BODY_TYPE PLUMBING
J 0
(-3300 3625);
DISPLAY 0.872340 (-3300 3625);
PAINT GREEN (-3300 3625);
DISPLAY INVISIBLE (-3300 3625);
FORCEPROP 1 LAST HDL_TAP TRUE
J 0
(-2975 3450);
DISPLAY 0.872340 (-2975 3450);
DISPLAY INVISIBLE (-2975 3450);
FORCEPROP 1 LAST PATH I217
J 0
(-3302 3575);
DISPLAY 0.872340 (-3302 3575);
PAINT GREEN (-3302 3575);
DISPLAY INVISIBLE (-3302 3575);
FORCEADD TAP..1
(-3300 3475);
FORCEPROP 3 LASTPIN (-3350 3475) SIG_NAME M_A_CPU1_SB_DQ<15>
J 0
(-3340 3485);
DISPLAY 0.659574 (-3340 3485);
PAINT MONO (-3340 3485);
DISPLAY INVISIBLE (-3340 3485);
FORCEPROP 1 LASTPIN (-3350 3475) BN 15
J 0
(-3362 3483);
DISPLAY 0.489362 (-3362 3483);
PAINT GREEN (-3362 3483);
FORCEPROP 2 LAST CDS_LIB mstr_standard
J 0
(-3300 3475);
DISPLAY 0.723404 (-3300 3475);
PAINT MONO (-3300 3475);
DISPLAY INVISIBLE (-3300 3475);
FORCEPROP 1 LAST BODY_TYPE PLUMBING
J 0
(-3300 3525);
DISPLAY 0.872340 (-3300 3525);
PAINT GREEN (-3300 3525);
DISPLAY INVISIBLE (-3300 3525);
FORCEPROP 1 LAST HDL_TAP TRUE
J 0
(-2975 3350);
DISPLAY 0.872340 (-2975 3350);
DISPLAY INVISIBLE (-2975 3350);
FORCEPROP 1 LAST PATH I218
J 0
(-3302 3475);
DISPLAY 0.872340 (-3302 3475);
PAINT GREEN (-3302 3475);
DISPLAY INVISIBLE (-3302 3475);
FORCEADD TAP..1
(-3300 3375);
FORCEPROP 3 LASTPIN (-3350 3375) SIG_NAME M_A_CPU1_SB_DQ<16>
J 0
(-3340 3385);
DISPLAY 0.659574 (-3340 3385);
PAINT MONO (-3340 3385);
DISPLAY INVISIBLE (-3340 3385);
FORCEPROP 1 LASTPIN (-3350 3375) BN 16
J 0
(-3362 3383);
DISPLAY 0.489362 (-3362 3383);
PAINT GREEN (-3362 3383);
FORCEPROP 2 LAST CDS_LIB mstr_standard
J 0
(-3300 3375);
DISPLAY 0.723404 (-3300 3375);
PAINT MONO (-3300 3375);
DISPLAY INVISIBLE (-3300 3375);
FORCEPROP 1 LAST BODY_TYPE PLUMBING
J 0
(-3300 3425);
DISPLAY 0.872340 (-3300 3425);
PAINT GREEN (-3300 3425);
DISPLAY INVISIBLE (-3300 3425);
FORCEPROP 1 LAST HDL_TAP TRUE
J 0
(-2975 3250);
DISPLAY 0.872340 (-2975 3250);
DISPLAY INVISIBLE (-2975 3250);
FORCEPROP 1 LAST PATH I219
J 0
(-3302 3375);
DISPLAY 0.872340 (-3302 3375);
PAINT GREEN (-3302 3375);
DISPLAY INVISIBLE (-3302 3375);
FORCEADD TAP..1
(-3300 3275);
FORCEPROP 3 LASTPIN (-3350 3275) SIG_NAME M_A_CPU1_SB_DQ<18>
J 0
(-3340 3285);
DISPLAY 0.659574 (-3340 3285);
PAINT MONO (-3340 3285);
DISPLAY INVISIBLE (-3340 3285);
FORCEPROP 1 LASTPIN (-3350 3275) BN 18
J 0
(-3362 3283);
DISPLAY 0.489362 (-3362 3283);
PAINT GREEN (-3362 3283);
FORCEPROP 2 LAST CDS_LIB mstr_standard
J 0
(-3300 3275);
DISPLAY 0.723404 (-3300 3275);
PAINT MONO (-3300 3275);
DISPLAY INVISIBLE (-3300 3275);
FORCEPROP 1 LAST BODY_TYPE PLUMBING
J 0
(-3300 3325);
DISPLAY 0.872340 (-3300 3325);
PAINT GREEN (-3300 3325);
DISPLAY INVISIBLE (-3300 3325);
FORCEPROP 1 LAST HDL_TAP TRUE
J 0
(-2975 3150);
DISPLAY 0.872340 (-2975 3150);
DISPLAY INVISIBLE (-2975 3150);
FORCEPROP 1 LAST PATH I220
J 0
(-3302 3275);
DISPLAY 0.872340 (-3302 3275);
PAINT GREEN (-3302 3275);
DISPLAY INVISIBLE (-3302 3275);
FORCEADD TAP..1
(-3300 3325);
FORCEPROP 3 LASTPIN (-3350 3325) SIG_NAME M_A_CPU1_SB_DQ<17>
J 0
(-3340 3335);
DISPLAY 0.659574 (-3340 3335);
PAINT MONO (-3340 3335);
DISPLAY INVISIBLE (-3340 3335);
FORCEPROP 1 LASTPIN (-3350 3325) BN 17
J 0
(-3362 3333);
DISPLAY 0.489362 (-3362 3333);
PAINT GREEN (-3362 3333);
FORCEPROP 2 LAST CDS_LIB mstr_standard
J 0
(-3300 3325);
DISPLAY 0.723404 (-3300 3325);
PAINT MONO (-3300 3325);
DISPLAY INVISIBLE (-3300 3325);
FORCEPROP 1 LAST BODY_TYPE PLUMBING
J 0
(-3300 3375);
DISPLAY 0.872340 (-3300 3375);
PAINT GREEN (-3300 3375);
DISPLAY INVISIBLE (-3300 3375);
FORCEPROP 1 LAST HDL_TAP TRUE
J 0
(-2975 3200);
DISPLAY 0.872340 (-2975 3200);
DISPLAY INVISIBLE (-2975 3200);
FORCEPROP 1 LAST PATH I221
J 0
(-3302 3325);
DISPLAY 0.872340 (-3302 3325);
PAINT GREEN (-3302 3325);
DISPLAY INVISIBLE (-3302 3325);
FORCEADD TAP..1
(-3300 3225);
FORCEPROP 3 LASTPIN (-3350 3225) SIG_NAME M_A_CPU1_SB_DQ<19>
J 0
(-3340 3235);
DISPLAY 0.659574 (-3340 3235);
PAINT MONO (-3340 3235);
DISPLAY INVISIBLE (-3340 3235);
FORCEPROP 1 LASTPIN (-3350 3225) BN 19
J 0
(-3362 3233);
DISPLAY 0.489362 (-3362 3233);
PAINT GREEN (-3362 3233);
FORCEPROP 2 LAST CDS_LIB mstr_standard
J 0
(-3300 3225);
DISPLAY 0.723404 (-3300 3225);
PAINT MONO (-3300 3225);
DISPLAY INVISIBLE (-3300 3225);
FORCEPROP 1 LAST BODY_TYPE PLUMBING
J 0
(-3300 3275);
DISPLAY 0.872340 (-3300 3275);
PAINT GREEN (-3300 3275);
DISPLAY INVISIBLE (-3300 3275);
FORCEPROP 1 LAST HDL_TAP TRUE
J 0
(-2975 3100);
DISPLAY 0.872340 (-2975 3100);
DISPLAY INVISIBLE (-2975 3100);
FORCEPROP 1 LAST PATH I222
J 0
(-3302 3225);
DISPLAY 0.872340 (-3302 3225);
PAINT GREEN (-3302 3225);
DISPLAY INVISIBLE (-3302 3225);
FORCEADD TAP..1
(-3300 3175);
FORCEPROP 3 LASTPIN (-3350 3175) SIG_NAME M_A_CPU1_SB_DQ<20>
J 0
(-3340 3185);
DISPLAY 0.659574 (-3340 3185);
PAINT MONO (-3340 3185);
DISPLAY INVISIBLE (-3340 3185);
FORCEPROP 1 LASTPIN (-3350 3175) BN 20
J 0
(-3362 3183);
DISPLAY 0.489362 (-3362 3183);
PAINT GREEN (-3362 3183);
FORCEPROP 2 LAST CDS_LIB mstr_standard
J 0
(-3300 3175);
DISPLAY 0.723404 (-3300 3175);
PAINT MONO (-3300 3175);
DISPLAY INVISIBLE (-3300 3175);
FORCEPROP 1 LAST BODY_TYPE PLUMBING
J 0
(-3300 3225);
DISPLAY 0.872340 (-3300 3225);
PAINT GREEN (-3300 3225);
DISPLAY INVISIBLE (-3300 3225);
FORCEPROP 1 LAST HDL_TAP TRUE
J 0
(-2975 3050);
DISPLAY 0.872340 (-2975 3050);
DISPLAY INVISIBLE (-2975 3050);
FORCEPROP 1 LAST PATH I223
J 0
(-3302 3175);
DISPLAY 0.872340 (-3302 3175);
PAINT GREEN (-3302 3175);
DISPLAY INVISIBLE (-3302 3175);
FORCEADD TAP..1
(-3300 3125);
FORCEPROP 3 LASTPIN (-3350 3125) SIG_NAME M_A_CPU1_SB_DQ<21>
J 0
(-3340 3135);
DISPLAY 0.659574 (-3340 3135);
PAINT MONO (-3340 3135);
DISPLAY INVISIBLE (-3340 3135);
FORCEPROP 1 LASTPIN (-3350 3125) BN 21
J 0
(-3362 3133);
DISPLAY 0.489362 (-3362 3133);
PAINT GREEN (-3362 3133);
FORCEPROP 2 LAST CDS_LIB mstr_standard
J 0
(-3300 3125);
DISPLAY 0.723404 (-3300 3125);
PAINT MONO (-3300 3125);
DISPLAY INVISIBLE (-3300 3125);
FORCEPROP 1 LAST BODY_TYPE PLUMBING
J 0
(-3300 3175);
DISPLAY 0.872340 (-3300 3175);
PAINT GREEN (-3300 3175);
DISPLAY INVISIBLE (-3300 3175);
FORCEPROP 1 LAST HDL_TAP TRUE
J 0
(-2975 3000);
DISPLAY 0.872340 (-2975 3000);
DISPLAY INVISIBLE (-2975 3000);
FORCEPROP 1 LAST PATH I224
J 0
(-3302 3125);
DISPLAY 0.872340 (-3302 3125);
PAINT GREEN (-3302 3125);
DISPLAY INVISIBLE (-3302 3125);
FORCEADD TAP..1
(-3300 3075);
FORCEPROP 3 LASTPIN (-3350 3075) SIG_NAME M_A_CPU1_SB_DQ<22>
J 0
(-3340 3085);
DISPLAY 0.659574 (-3340 3085);
PAINT MONO (-3340 3085);
DISPLAY INVISIBLE (-3340 3085);
FORCEPROP 1 LASTPIN (-3350 3075) BN 22
J 0
(-3362 3083);
DISPLAY 0.489362 (-3362 3083);
PAINT GREEN (-3362 3083);
FORCEPROP 2 LAST CDS_LIB mstr_standard
J 0
(-3300 3075);
DISPLAY 0.723404 (-3300 3075);
PAINT MONO (-3300 3075);
DISPLAY INVISIBLE (-3300 3075);
FORCEPROP 1 LAST BODY_TYPE PLUMBING
J 0
(-3300 3125);
DISPLAY 0.872340 (-3300 3125);
PAINT GREEN (-3300 3125);
DISPLAY INVISIBLE (-3300 3125);
FORCEPROP 1 LAST HDL_TAP TRUE
J 0
(-2975 2950);
DISPLAY 0.872340 (-2975 2950);
DISPLAY INVISIBLE (-2975 2950);
FORCEPROP 1 LAST PATH I225
J 0
(-3302 3075);
DISPLAY 0.872340 (-3302 3075);
PAINT GREEN (-3302 3075);
DISPLAY INVISIBLE (-3302 3075);
FORCEADD TAP..1
(-3300 3025);
FORCEPROP 3 LASTPIN (-3350 3025) SIG_NAME M_A_CPU1_SB_DQ<23>
J 0
(-3340 3035);
DISPLAY 0.659574 (-3340 3035);
PAINT MONO (-3340 3035);
DISPLAY INVISIBLE (-3340 3035);
FORCEPROP 1 LASTPIN (-3350 3025) BN 23
J 0
(-3362 3033);
DISPLAY 0.489362 (-3362 3033);
PAINT GREEN (-3362 3033);
FORCEPROP 2 LAST CDS_LIB mstr_standard
J 0
(-3300 3025);
DISPLAY 0.723404 (-3300 3025);
PAINT MONO (-3300 3025);
DISPLAY INVISIBLE (-3300 3025);
FORCEPROP 1 LAST BODY_TYPE PLUMBING
J 0
(-3300 3075);
DISPLAY 0.872340 (-3300 3075);
PAINT GREEN (-3300 3075);
DISPLAY INVISIBLE (-3300 3075);
FORCEPROP 1 LAST HDL_TAP TRUE
J 0
(-2975 2900);
DISPLAY 0.872340 (-2975 2900);
DISPLAY INVISIBLE (-2975 2900);
FORCEPROP 1 LAST PATH I226
J 0
(-3302 3025);
DISPLAY 0.872340 (-3302 3025);
PAINT GREEN (-3302 3025);
DISPLAY INVISIBLE (-3302 3025);
FORCEADD TAP..1
(-3300 2925);
FORCEPROP 3 LASTPIN (-3350 2925) SIG_NAME M_A_CPU1_SB_DQ<24>
J 0
(-3340 2935);
DISPLAY 0.659574 (-3340 2935);
PAINT MONO (-3340 2935);
DISPLAY INVISIBLE (-3340 2935);
FORCEPROP 1 LASTPIN (-3350 2925) BN 24
J 0
(-3362 2933);
DISPLAY 0.489362 (-3362 2933);
PAINT GREEN (-3362 2933);
FORCEPROP 2 LAST CDS_LIB mstr_standard
J 0
(-3300 2925);
DISPLAY 0.723404 (-3300 2925);
PAINT MONO (-3300 2925);
DISPLAY INVISIBLE (-3300 2925);
FORCEPROP 1 LAST BODY_TYPE PLUMBING
J 0
(-3300 2975);
DISPLAY 0.872340 (-3300 2975);
PAINT GREEN (-3300 2975);
DISPLAY INVISIBLE (-3300 2975);
FORCEPROP 1 LAST HDL_TAP TRUE
J 0
(-2975 2800);
DISPLAY 0.872340 (-2975 2800);
DISPLAY INVISIBLE (-2975 2800);
FORCEPROP 1 LAST PATH I227
J 0
(-3302 2925);
DISPLAY 0.872340 (-3302 2925);
PAINT GREEN (-3302 2925);
DISPLAY INVISIBLE (-3302 2925);
FORCEADD TAP..1
(-3300 2875);
FORCEPROP 3 LASTPIN (-3350 2875) SIG_NAME M_A_CPU1_SB_DQ<25>
J 0
(-3340 2885);
DISPLAY 0.659574 (-3340 2885);
PAINT MONO (-3340 2885);
DISPLAY INVISIBLE (-3340 2885);
FORCEPROP 1 LASTPIN (-3350 2875) BN 25
J 0
(-3362 2883);
DISPLAY 0.489362 (-3362 2883);
PAINT GREEN (-3362 2883);
FORCEPROP 2 LAST CDS_LIB mstr_standard
J 0
(-3300 2875);
DISPLAY 0.723404 (-3300 2875);
PAINT MONO (-3300 2875);
DISPLAY INVISIBLE (-3300 2875);
FORCEPROP 1 LAST BODY_TYPE PLUMBING
J 0
(-3300 2925);
DISPLAY 0.872340 (-3300 2925);
PAINT GREEN (-3300 2925);
DISPLAY INVISIBLE (-3300 2925);
FORCEPROP 1 LAST HDL_TAP TRUE
J 0
(-2975 2750);
DISPLAY 0.872340 (-2975 2750);
DISPLAY INVISIBLE (-2975 2750);
FORCEPROP 1 LAST PATH I228
J 0
(-3302 2875);
DISPLAY 0.872340 (-3302 2875);
PAINT GREEN (-3302 2875);
DISPLAY INVISIBLE (-3302 2875);
FORCEADD TAP..1
(-3300 2825);
FORCEPROP 3 LASTPIN (-3350 2825) SIG_NAME M_A_CPU1_SB_DQ<26>
J 0
(-3340 2835);
DISPLAY 0.659574 (-3340 2835);
PAINT MONO (-3340 2835);
DISPLAY INVISIBLE (-3340 2835);
FORCEPROP 1 LASTPIN (-3350 2825) BN 26
J 0
(-3362 2833);
DISPLAY 0.489362 (-3362 2833);
PAINT GREEN (-3362 2833);
FORCEPROP 2 LAST CDS_LIB mstr_standard
J 0
(-3300 2825);
DISPLAY 0.723404 (-3300 2825);
PAINT MONO (-3300 2825);
DISPLAY INVISIBLE (-3300 2825);
FORCEPROP 1 LAST BODY_TYPE PLUMBING
J 0
(-3300 2875);
DISPLAY 0.872340 (-3300 2875);
PAINT GREEN (-3300 2875);
DISPLAY INVISIBLE (-3300 2875);
FORCEPROP 1 LAST HDL_TAP TRUE
J 0
(-2975 2700);
DISPLAY 0.872340 (-2975 2700);
DISPLAY INVISIBLE (-2975 2700);
FORCEPROP 1 LAST PATH I229
J 0
(-3302 2825);
DISPLAY 0.872340 (-3302 2825);
PAINT GREEN (-3302 2825);
DISPLAY INVISIBLE (-3302 2825);
FORCEADD TAP..1
(-3300 2775);
FORCEPROP 3 LASTPIN (-3350 2775) SIG_NAME M_A_CPU1_SB_DQ<27>
J 0
(-3340 2785);
DISPLAY 0.659574 (-3340 2785);
PAINT MONO (-3340 2785);
DISPLAY INVISIBLE (-3340 2785);
FORCEPROP 1 LASTPIN (-3350 2775) BN 27
J 0
(-3362 2783);
DISPLAY 0.489362 (-3362 2783);
PAINT GREEN (-3362 2783);
FORCEPROP 2 LAST CDS_LIB mstr_standard
J 0
(-3300 2775);
DISPLAY 0.723404 (-3300 2775);
PAINT MONO (-3300 2775);
DISPLAY INVISIBLE (-3300 2775);
FORCEPROP 1 LAST BODY_TYPE PLUMBING
J 0
(-3300 2825);
DISPLAY 0.872340 (-3300 2825);
PAINT GREEN (-3300 2825);
DISPLAY INVISIBLE (-3300 2825);
FORCEPROP 1 LAST HDL_TAP TRUE
J 0
(-2975 2650);
DISPLAY 0.872340 (-2975 2650);
DISPLAY INVISIBLE (-2975 2650);
FORCEPROP 1 LAST PATH I230
J 0
(-3302 2775);
DISPLAY 0.872340 (-3302 2775);
PAINT GREEN (-3302 2775);
DISPLAY INVISIBLE (-3302 2775);
FORCEADD TAP..1
(-3300 2725);
FORCEPROP 3 LASTPIN (-3350 2725) SIG_NAME M_A_CPU1_SB_DQ<28>
J 0
(-3340 2735);
DISPLAY 0.659574 (-3340 2735);
PAINT MONO (-3340 2735);
DISPLAY INVISIBLE (-3340 2735);
FORCEPROP 1 LASTPIN (-3350 2725) BN 28
J 0
(-3362 2733);
DISPLAY 0.489362 (-3362 2733);
PAINT GREEN (-3362 2733);
FORCEPROP 2 LAST CDS_LIB mstr_standard
J 0
(-3300 2725);
DISPLAY 0.723404 (-3300 2725);
PAINT MONO (-3300 2725);
DISPLAY INVISIBLE (-3300 2725);
FORCEPROP 1 LAST BODY_TYPE PLUMBING
J 0
(-3300 2775);
DISPLAY 0.872340 (-3300 2775);
PAINT GREEN (-3300 2775);
DISPLAY INVISIBLE (-3300 2775);
FORCEPROP 1 LAST HDL_TAP TRUE
J 0
(-2975 2600);
DISPLAY 0.872340 (-2975 2600);
DISPLAY INVISIBLE (-2975 2600);
FORCEPROP 1 LAST PATH I231
J 0
(-3302 2725);
DISPLAY 0.872340 (-3302 2725);
PAINT GREEN (-3302 2725);
DISPLAY INVISIBLE (-3302 2725);
FORCEADD TAP..1
(-3300 2675);
FORCEPROP 3 LASTPIN (-3350 2675) SIG_NAME M_A_CPU1_SB_DQ<29>
J 0
(-3340 2685);
DISPLAY 0.659574 (-3340 2685);
PAINT MONO (-3340 2685);
DISPLAY INVISIBLE (-3340 2685);
FORCEPROP 1 LASTPIN (-3350 2675) BN 29
J 0
(-3362 2683);
DISPLAY 0.489362 (-3362 2683);
PAINT GREEN (-3362 2683);
FORCEPROP 2 LAST CDS_LIB mstr_standard
J 0
(-3300 2675);
DISPLAY 0.723404 (-3300 2675);
PAINT MONO (-3300 2675);
DISPLAY INVISIBLE (-3300 2675);
FORCEPROP 1 LAST BODY_TYPE PLUMBING
J 0
(-3300 2725);
DISPLAY 0.872340 (-3300 2725);
PAINT GREEN (-3300 2725);
DISPLAY INVISIBLE (-3300 2725);
FORCEPROP 1 LAST HDL_TAP TRUE
J 0
(-2975 2550);
DISPLAY 0.872340 (-2975 2550);
DISPLAY INVISIBLE (-2975 2550);
FORCEPROP 1 LAST PATH I232
J 0
(-3302 2675);
DISPLAY 0.872340 (-3302 2675);
PAINT GREEN (-3302 2675);
DISPLAY INVISIBLE (-3302 2675);
FORCEADD TAP..1
(-3300 2625);
FORCEPROP 3 LASTPIN (-3350 2625) SIG_NAME M_A_CPU1_SB_DQ<30>
J 0
(-3340 2635);
DISPLAY 0.659574 (-3340 2635);
PAINT MONO (-3340 2635);
DISPLAY INVISIBLE (-3340 2635);
FORCEPROP 1 LASTPIN (-3350 2625) BN 30
J 0
(-3362 2633);
DISPLAY 0.489362 (-3362 2633);
PAINT GREEN (-3362 2633);
FORCEPROP 2 LAST CDS_LIB mstr_standard
J 0
(-3300 2625);
DISPLAY 0.723404 (-3300 2625);
PAINT MONO (-3300 2625);
DISPLAY INVISIBLE (-3300 2625);
FORCEPROP 1 LAST BODY_TYPE PLUMBING
J 0
(-3300 2675);
DISPLAY 0.872340 (-3300 2675);
PAINT GREEN (-3300 2675);
DISPLAY INVISIBLE (-3300 2675);
FORCEPROP 1 LAST HDL_TAP TRUE
J 0
(-2975 2500);
DISPLAY 0.872340 (-2975 2500);
DISPLAY INVISIBLE (-2975 2500);
FORCEPROP 1 LAST PATH I233
J 0
(-3302 2625);
DISPLAY 0.872340 (-3302 2625);
PAINT GREEN (-3302 2625);
DISPLAY INVISIBLE (-3302 2625);
FORCEADD TAP..1
(-3300 2575);
FORCEPROP 3 LASTPIN (-3350 2575) SIG_NAME M_A_CPU1_SB_DQ<31>
J 0
(-3340 2585);
DISPLAY 0.659574 (-3340 2585);
PAINT MONO (-3340 2585);
DISPLAY INVISIBLE (-3340 2585);
FORCEPROP 1 LASTPIN (-3350 2575) BN 31
J 0
(-3362 2583);
DISPLAY 0.489362 (-3362 2583);
PAINT GREEN (-3362 2583);
FORCEPROP 2 LAST CDS_LIB mstr_standard
J 0
(-3300 2575);
DISPLAY 0.723404 (-3300 2575);
PAINT MONO (-3300 2575);
DISPLAY INVISIBLE (-3300 2575);
FORCEPROP 1 LAST BODY_TYPE PLUMBING
J 0
(-3300 2625);
DISPLAY 0.872340 (-3300 2625);
PAINT GREEN (-3300 2625);
DISPLAY INVISIBLE (-3300 2625);
FORCEPROP 1 LAST HDL_TAP TRUE
J 0
(-2975 2450);
DISPLAY 0.872340 (-2975 2450);
DISPLAY INVISIBLE (-2975 2450);
FORCEPROP 1 LAST PATH I234
J 0
(-3302 2575);
DISPLAY 0.872340 (-3302 2575);
PAINT GREEN (-3302 2575);
DISPLAY INVISIBLE (-3302 2575);
FORCEADD TAP..1
(-3300 2475);
FORCEPROP 3 LASTPIN (-3350 2475) SIG_NAME M_A_CPU1_SA_CB<0>
J 0
(-3340 2485);
DISPLAY 0.659574 (-3340 2485);
PAINT MONO (-3340 2485);
DISPLAY INVISIBLE (-3340 2485);
FORCEPROP 1 LASTPIN (-3350 2475) BN 0
J 0
(-3362 2483);
DISPLAY 0.489362 (-3362 2483);
PAINT GREEN (-3362 2483);
FORCEPROP 2 LAST CDS_LIB mstr_standard
J 2
(-3300 2475);
DISPLAY 0.723404 (-3300 2475);
PAINT MONO (-3300 2475);
DISPLAY INVISIBLE (-3300 2475);
FORCEPROP 1 LAST BODY_TYPE PLUMBING
J 0
(-3300 2525);
DISPLAY 0.872340 (-3300 2525);
PAINT GREEN (-3300 2525);
DISPLAY INVISIBLE (-3300 2525);
FORCEPROP 1 LAST HDL_TAP TRUE
J 0
(-2975 2350);
DISPLAY 0.872340 (-2975 2350);
DISPLAY INVISIBLE (-2975 2350);
FORCEPROP 1 LAST PATH I235
J 0
(-3302 2475);
DISPLAY 0.872340 (-3302 2475);
PAINT GREEN (-3302 2475);
DISPLAY INVISIBLE (-3302 2475);
FORCEADD TAP..1
(-3300 2375);
FORCEPROP 3 LASTPIN (-3350 2375) SIG_NAME M_A_CPU1_SA_CB<2>
J 0
(-3340 2385);
DISPLAY 0.659574 (-3340 2385);
PAINT MONO (-3340 2385);
DISPLAY INVISIBLE (-3340 2385);
FORCEPROP 1 LASTPIN (-3350 2375) BN 2
J 0
(-3362 2383);
DISPLAY 0.489362 (-3362 2383);
PAINT GREEN (-3362 2383);
FORCEPROP 2 LAST CDS_LIB mstr_standard
J 2
(-3300 2375);
DISPLAY 0.723404 (-3300 2375);
PAINT MONO (-3300 2375);
DISPLAY INVISIBLE (-3300 2375);
FORCEPROP 1 LAST BODY_TYPE PLUMBING
J 0
(-3300 2425);
DISPLAY 0.872340 (-3300 2425);
PAINT GREEN (-3300 2425);
DISPLAY INVISIBLE (-3300 2425);
FORCEPROP 1 LAST HDL_TAP TRUE
J 0
(-2975 2250);
DISPLAY 0.872340 (-2975 2250);
DISPLAY INVISIBLE (-2975 2250);
FORCEPROP 1 LAST PATH I236
J 0
(-3302 2375);
DISPLAY 0.872340 (-3302 2375);
PAINT GREEN (-3302 2375);
DISPLAY INVISIBLE (-3302 2375);
FORCEADD TAP..1
(-3300 2425);
FORCEPROP 3 LASTPIN (-3350 2425) SIG_NAME M_A_CPU1_SA_CB<1>
J 0
(-3340 2435);
DISPLAY 0.659574 (-3340 2435);
PAINT MONO (-3340 2435);
DISPLAY INVISIBLE (-3340 2435);
FORCEPROP 1 LASTPIN (-3350 2425) BN 1
J 0
(-3362 2433);
DISPLAY 0.489362 (-3362 2433);
PAINT GREEN (-3362 2433);
FORCEPROP 2 LAST CDS_LIB mstr_standard
J 2
(-3300 2425);
DISPLAY 0.723404 (-3300 2425);
PAINT MONO (-3300 2425);
DISPLAY INVISIBLE (-3300 2425);
FORCEPROP 1 LAST BODY_TYPE PLUMBING
J 0
(-3300 2475);
DISPLAY 0.872340 (-3300 2475);
PAINT GREEN (-3300 2475);
DISPLAY INVISIBLE (-3300 2475);
FORCEPROP 1 LAST HDL_TAP TRUE
J 0
(-2975 2300);
DISPLAY 0.872340 (-2975 2300);
DISPLAY INVISIBLE (-2975 2300);
FORCEPROP 1 LAST PATH I237
J 0
(-3302 2425);
DISPLAY 0.872340 (-3302 2425);
PAINT GREEN (-3302 2425);
DISPLAY INVISIBLE (-3302 2425);
FORCEADD TAP..1
(-3300 2325);
FORCEPROP 3 LASTPIN (-3350 2325) SIG_NAME M_A_CPU1_SA_CB<3>
J 0
(-3340 2335);
DISPLAY 0.659574 (-3340 2335);
PAINT MONO (-3340 2335);
DISPLAY INVISIBLE (-3340 2335);
FORCEPROP 1 LASTPIN (-3350 2325) BN 3
J 0
(-3362 2333);
DISPLAY 0.489362 (-3362 2333);
PAINT GREEN (-3362 2333);
FORCEPROP 2 LAST CDS_LIB mstr_standard
J 2
(-3300 2325);
DISPLAY 0.723404 (-3300 2325);
PAINT MONO (-3300 2325);
DISPLAY INVISIBLE (-3300 2325);
FORCEPROP 1 LAST BODY_TYPE PLUMBING
J 0
(-3300 2375);
DISPLAY 0.872340 (-3300 2375);
PAINT GREEN (-3300 2375);
DISPLAY INVISIBLE (-3300 2375);
FORCEPROP 1 LAST HDL_TAP TRUE
J 0
(-2975 2200);
DISPLAY 0.872340 (-2975 2200);
DISPLAY INVISIBLE (-2975 2200);
FORCEPROP 1 LAST PATH I238
J 0
(-3302 2325);
DISPLAY 0.872340 (-3302 2325);
PAINT GREEN (-3302 2325);
DISPLAY INVISIBLE (-3302 2325);
FORCEADD TAP..1
(-3300 2275);
FORCEPROP 3 LASTPIN (-3350 2275) SIG_NAME M_A_CPU1_SA_CB<4>
J 0
(-3340 2285);
DISPLAY 0.659574 (-3340 2285);
PAINT MONO (-3340 2285);
DISPLAY INVISIBLE (-3340 2285);
FORCEPROP 1 LASTPIN (-3350 2275) BN 4
J 0
(-3362 2283);
DISPLAY 0.489362 (-3362 2283);
PAINT GREEN (-3362 2283);
FORCEPROP 2 LAST CDS_LIB mstr_standard
J 2
(-3300 2275);
DISPLAY 0.723404 (-3300 2275);
PAINT MONO (-3300 2275);
DISPLAY INVISIBLE (-3300 2275);
FORCEPROP 1 LAST BODY_TYPE PLUMBING
J 0
(-3300 2325);
DISPLAY 0.872340 (-3300 2325);
PAINT GREEN (-3300 2325);
DISPLAY INVISIBLE (-3300 2325);
FORCEPROP 1 LAST HDL_TAP TRUE
J 0
(-2975 2150);
DISPLAY 0.872340 (-2975 2150);
DISPLAY INVISIBLE (-2975 2150);
FORCEPROP 1 LAST PATH I239
J 0
(-3302 2275);
DISPLAY 0.872340 (-3302 2275);
PAINT GREEN (-3302 2275);
DISPLAY INVISIBLE (-3302 2275);
FORCEADD TAP..1
(-3300 2225);
FORCEPROP 3 LASTPIN (-3350 2225) SIG_NAME M_A_CPU1_SA_CB<5>
J 0
(-3340 2235);
DISPLAY 0.659574 (-3340 2235);
PAINT MONO (-3340 2235);
DISPLAY INVISIBLE (-3340 2235);
FORCEPROP 1 LASTPIN (-3350 2225) BN 5
J 0
(-3362 2233);
DISPLAY 0.489362 (-3362 2233);
PAINT GREEN (-3362 2233);
FORCEPROP 2 LAST CDS_LIB mstr_standard
J 2
(-3300 2225);
DISPLAY 0.723404 (-3300 2225);
PAINT MONO (-3300 2225);
DISPLAY INVISIBLE (-3300 2225);
FORCEPROP 1 LAST BODY_TYPE PLUMBING
J 0
(-3300 2275);
DISPLAY 0.872340 (-3300 2275);
PAINT GREEN (-3300 2275);
DISPLAY INVISIBLE (-3300 2275);
FORCEPROP 1 LAST HDL_TAP TRUE
J 0
(-2975 2100);
DISPLAY 0.872340 (-2975 2100);
DISPLAY INVISIBLE (-2975 2100);
FORCEPROP 1 LAST PATH I240
J 0
(-3302 2225);
DISPLAY 0.872340 (-3302 2225);
PAINT GREEN (-3302 2225);
DISPLAY INVISIBLE (-3302 2225);
FORCEADD TAP..1
(-3300 2175);
FORCEPROP 3 LASTPIN (-3350 2175) SIG_NAME M_A_CPU1_SA_CB<6>
J 0
(-3340 2185);
DISPLAY 0.659574 (-3340 2185);
PAINT MONO (-3340 2185);
DISPLAY INVISIBLE (-3340 2185);
FORCEPROP 1 LASTPIN (-3350 2175) BN 6
J 0
(-3362 2183);
DISPLAY 0.489362 (-3362 2183);
PAINT GREEN (-3362 2183);
FORCEPROP 2 LAST CDS_LIB mstr_standard
J 2
(-3300 2175);
DISPLAY 0.723404 (-3300 2175);
PAINT MONO (-3300 2175);
DISPLAY INVISIBLE (-3300 2175);
FORCEPROP 1 LAST BODY_TYPE PLUMBING
J 0
(-3300 2225);
DISPLAY 0.872340 (-3300 2225);
PAINT GREEN (-3300 2225);
DISPLAY INVISIBLE (-3300 2225);
FORCEPROP 1 LAST HDL_TAP TRUE
J 0
(-2975 2050);
DISPLAY 0.872340 (-2975 2050);
DISPLAY INVISIBLE (-2975 2050);
FORCEPROP 1 LAST PATH I241
J 0
(-3302 2175);
DISPLAY 0.872340 (-3302 2175);
PAINT GREEN (-3302 2175);
DISPLAY INVISIBLE (-3302 2175);
FORCEADD TAP..1
(-3300 2125);
FORCEPROP 3 LASTPIN (-3350 2125) SIG_NAME M_A_CPU1_SA_CB<7>
J 0
(-3340 2135);
DISPLAY 0.659574 (-3340 2135);
PAINT MONO (-3340 2135);
DISPLAY INVISIBLE (-3340 2135);
FORCEPROP 1 LASTPIN (-3350 2125) BN 7
J 0
(-3362 2133);
DISPLAY 0.489362 (-3362 2133);
PAINT GREEN (-3362 2133);
FORCEPROP 2 LAST CDS_LIB mstr_standard
J 2
(-3300 2125);
DISPLAY 0.723404 (-3300 2125);
PAINT MONO (-3300 2125);
DISPLAY INVISIBLE (-3300 2125);
FORCEPROP 1 LAST BODY_TYPE PLUMBING
J 0
(-3300 2175);
DISPLAY 0.872340 (-3300 2175);
PAINT GREEN (-3300 2175);
DISPLAY INVISIBLE (-3300 2175);
FORCEPROP 1 LAST HDL_TAP TRUE
J 0
(-2975 2000);
DISPLAY 0.872340 (-2975 2000);
DISPLAY INVISIBLE (-2975 2000);
FORCEPROP 1 LAST PATH I242
J 0
(-3302 2125);
DISPLAY 0.872340 (-3302 2125);
PAINT GREEN (-3302 2125);
DISPLAY INVISIBLE (-3302 2125);
FORCEADD OFFPAGE..6
R 2
(-2700 2075);
FORCEPROP 2 LAST $XR0 98 
J 0
(-2486 2075);
DISPLAY 0.638298 (-2486 2075);
PAINT MONO (-2486 2075);
FORCEPROP 2 LAST CDS_LIB mstr_standard
J 2
(-2700 2075);
DISPLAY 0.723404 (-2700 2075);
PAINT MONO (-2700 2075);
DISPLAY INVISIBLE (-2700 2075);
FORCEPROP 1 LAST OFFPAGE TRUE
J 2
(-3025 1950);
DISPLAY 0.872340 (-3025 1950);
PAINT GREEN (-3025 1950);
DISPLAY INVISIBLE (-3025 1950);
FORCEPROP 1 LAST COMMENT_BODY TRUE
J 2
(-2800 2000);
DISPLAY 0.872340 (-2800 2000);
PAINT GREEN (-2800 2000);
DISPLAY INVISIBLE (-2800 2000);
FORCEPROP 2 LAST PATH I243
J 0
(-2475 2125);
DISPLAY 1.021277 (-2475 2125);
DISPLAY INVISIBLE (-2475 2125);
FORCEADD TAP..1
(-3300 2025);
FORCEPROP 3 LASTPIN (-3350 2025) SIG_NAME M_A_CPU1_SB_CB<0>
J 0
(-3340 2035);
DISPLAY 0.659574 (-3340 2035);
PAINT MONO (-3340 2035);
DISPLAY INVISIBLE (-3340 2035);
FORCEPROP 1 LASTPIN (-3350 2025) BN 0
J 0
(-3362 2033);
DISPLAY 0.489362 (-3362 2033);
PAINT GREEN (-3362 2033);
FORCEPROP 2 LAST CDS_LIB mstr_standard
J 2
(-3300 2025);
DISPLAY 0.723404 (-3300 2025);
PAINT MONO (-3300 2025);
DISPLAY INVISIBLE (-3300 2025);
FORCEPROP 1 LAST BODY_TYPE PLUMBING
J 0
(-3300 2075);
DISPLAY 0.872340 (-3300 2075);
PAINT GREEN (-3300 2075);
DISPLAY INVISIBLE (-3300 2075);
FORCEPROP 1 LAST HDL_TAP TRUE
J 0
(-2975 1900);
DISPLAY 0.872340 (-2975 1900);
DISPLAY INVISIBLE (-2975 1900);
FORCEPROP 1 LAST PATH I244
J 0
(-3302 2025);
DISPLAY 0.872340 (-3302 2025);
PAINT GREEN (-3302 2025);
DISPLAY INVISIBLE (-3302 2025);
FORCEADD TAP..1
(-3300 1975);
FORCEPROP 3 LASTPIN (-3350 1975) SIG_NAME M_A_CPU1_SB_CB<1>
J 0
(-3340 1985);
DISPLAY 0.659574 (-3340 1985);
PAINT MONO (-3340 1985);
DISPLAY INVISIBLE (-3340 1985);
FORCEPROP 1 LASTPIN (-3350 1975) BN 1
J 0
(-3362 1983);
DISPLAY 0.489362 (-3362 1983);
PAINT GREEN (-3362 1983);
FORCEPROP 2 LAST CDS_LIB mstr_standard
J 2
(-3300 1975);
DISPLAY 0.723404 (-3300 1975);
PAINT MONO (-3300 1975);
DISPLAY INVISIBLE (-3300 1975);
FORCEPROP 1 LAST BODY_TYPE PLUMBING
J 0
(-3300 2025);
DISPLAY 0.872340 (-3300 2025);
PAINT GREEN (-3300 2025);
DISPLAY INVISIBLE (-3300 2025);
FORCEPROP 1 LAST HDL_TAP TRUE
J 0
(-2975 1850);
DISPLAY 0.872340 (-2975 1850);
DISPLAY INVISIBLE (-2975 1850);
FORCEPROP 1 LAST PATH I245
J 0
(-3302 1975);
DISPLAY 0.872340 (-3302 1975);
PAINT GREEN (-3302 1975);
DISPLAY INVISIBLE (-3302 1975);
FORCEADD TAP..1
(-3300 1925);
FORCEPROP 3 LASTPIN (-3350 1925) SIG_NAME M_A_CPU1_SB_CB<2>
J 0
(-3340 1935);
DISPLAY 0.659574 (-3340 1935);
PAINT MONO (-3340 1935);
DISPLAY INVISIBLE (-3340 1935);
FORCEPROP 1 LASTPIN (-3350 1925) BN 2
J 0
(-3362 1933);
DISPLAY 0.489362 (-3362 1933);
PAINT GREEN (-3362 1933);
FORCEPROP 2 LAST CDS_LIB mstr_standard
J 2
(-3300 1925);
DISPLAY 0.723404 (-3300 1925);
PAINT MONO (-3300 1925);
DISPLAY INVISIBLE (-3300 1925);
FORCEPROP 1 LAST BODY_TYPE PLUMBING
J 0
(-3300 1975);
DISPLAY 0.872340 (-3300 1975);
PAINT GREEN (-3300 1975);
DISPLAY INVISIBLE (-3300 1975);
FORCEPROP 1 LAST HDL_TAP TRUE
J 0
(-2975 1800);
DISPLAY 0.872340 (-2975 1800);
DISPLAY INVISIBLE (-2975 1800);
FORCEPROP 1 LAST PATH I246
J 0
(-3302 1925);
DISPLAY 0.872340 (-3302 1925);
PAINT GREEN (-3302 1925);
DISPLAY INVISIBLE (-3302 1925);
FORCEADD TAP..1
(-3300 1825);
FORCEPROP 3 LASTPIN (-3350 1825) SIG_NAME M_A_CPU1_SB_CB<4>
J 0
(-3340 1835);
DISPLAY 0.659574 (-3340 1835);
PAINT MONO (-3340 1835);
DISPLAY INVISIBLE (-3340 1835);
FORCEPROP 1 LASTPIN (-3350 1825) BN 4
J 0
(-3362 1833);
DISPLAY 0.489362 (-3362 1833);
PAINT GREEN (-3362 1833);
FORCEPROP 2 LAST CDS_LIB mstr_standard
J 2
(-3300 1825);
DISPLAY 0.723404 (-3300 1825);
PAINT MONO (-3300 1825);
DISPLAY INVISIBLE (-3300 1825);
FORCEPROP 1 LAST BODY_TYPE PLUMBING
J 0
(-3300 1875);
DISPLAY 0.872340 (-3300 1875);
PAINT GREEN (-3300 1875);
DISPLAY INVISIBLE (-3300 1875);
FORCEPROP 1 LAST HDL_TAP TRUE
J 0
(-2975 1700);
DISPLAY 0.872340 (-2975 1700);
DISPLAY INVISIBLE (-2975 1700);
FORCEPROP 1 LAST PATH I247
J 0
(-3302 1825);
DISPLAY 0.872340 (-3302 1825);
PAINT GREEN (-3302 1825);
DISPLAY INVISIBLE (-3302 1825);
FORCEADD TAP..1
(-3300 1875);
FORCEPROP 3 LASTPIN (-3350 1875) SIG_NAME M_A_CPU1_SB_CB<3>
J 0
(-3340 1885);
DISPLAY 0.659574 (-3340 1885);
PAINT MONO (-3340 1885);
DISPLAY INVISIBLE (-3340 1885);
FORCEPROP 1 LASTPIN (-3350 1875) BN 3
J 0
(-3362 1883);
DISPLAY 0.489362 (-3362 1883);
PAINT GREEN (-3362 1883);
FORCEPROP 2 LAST CDS_LIB mstr_standard
J 2
(-3300 1875);
DISPLAY 0.723404 (-3300 1875);
PAINT MONO (-3300 1875);
DISPLAY INVISIBLE (-3300 1875);
FORCEPROP 1 LAST BODY_TYPE PLUMBING
J 0
(-3300 1925);
DISPLAY 0.872340 (-3300 1925);
PAINT GREEN (-3300 1925);
DISPLAY INVISIBLE (-3300 1925);
FORCEPROP 1 LAST HDL_TAP TRUE
J 0
(-2975 1750);
DISPLAY 0.872340 (-2975 1750);
DISPLAY INVISIBLE (-2975 1750);
FORCEPROP 1 LAST PATH I248
J 0
(-3302 1875);
DISPLAY 0.872340 (-3302 1875);
PAINT GREEN (-3302 1875);
DISPLAY INVISIBLE (-3302 1875);
FORCEADD TAP..1
(-3300 1775);
FORCEPROP 3 LASTPIN (-3350 1775) SIG_NAME M_A_CPU1_SB_CB<5>
J 0
(-3340 1785);
DISPLAY 0.659574 (-3340 1785);
PAINT MONO (-3340 1785);
DISPLAY INVISIBLE (-3340 1785);
FORCEPROP 1 LASTPIN (-3350 1775) BN 5
J 0
(-3362 1783);
DISPLAY 0.489362 (-3362 1783);
PAINT GREEN (-3362 1783);
FORCEPROP 2 LAST CDS_LIB mstr_standard
J 2
(-3300 1775);
DISPLAY 0.723404 (-3300 1775);
PAINT MONO (-3300 1775);
DISPLAY INVISIBLE (-3300 1775);
FORCEPROP 1 LAST BODY_TYPE PLUMBING
J 0
(-3300 1825);
DISPLAY 0.872340 (-3300 1825);
PAINT GREEN (-3300 1825);
DISPLAY INVISIBLE (-3300 1825);
FORCEPROP 1 LAST HDL_TAP TRUE
J 0
(-2975 1650);
DISPLAY 0.872340 (-2975 1650);
DISPLAY INVISIBLE (-2975 1650);
FORCEPROP 1 LAST PATH I249
J 0
(-3302 1775);
DISPLAY 0.872340 (-3302 1775);
PAINT GREEN (-3302 1775);
DISPLAY INVISIBLE (-3302 1775);
FORCEADD TAP..1
(-3300 1675);
FORCEPROP 3 LASTPIN (-3350 1675) SIG_NAME M_A_CPU1_SB_CB<7>
J 0
(-3340 1685);
DISPLAY 0.659574 (-3340 1685);
PAINT MONO (-3340 1685);
DISPLAY INVISIBLE (-3340 1685);
FORCEPROP 1 LASTPIN (-3350 1675) BN 7
J 0
(-3362 1683);
DISPLAY 0.489362 (-3362 1683);
PAINT GREEN (-3362 1683);
FORCEPROP 2 LAST CDS_LIB mstr_standard
J 2
(-3300 1675);
DISPLAY 0.723404 (-3300 1675);
PAINT MONO (-3300 1675);
DISPLAY INVISIBLE (-3300 1675);
FORCEPROP 1 LAST BODY_TYPE PLUMBING
J 0
(-3300 1725);
DISPLAY 0.872340 (-3300 1725);
PAINT GREEN (-3300 1725);
DISPLAY INVISIBLE (-3300 1725);
FORCEPROP 1 LAST HDL_TAP TRUE
J 0
(-2975 1550);
DISPLAY 0.872340 (-2975 1550);
DISPLAY INVISIBLE (-2975 1550);
FORCEPROP 1 LAST PATH I250
J 0
(-3302 1675);
DISPLAY 0.872340 (-3302 1675);
PAINT GREEN (-3302 1675);
DISPLAY INVISIBLE (-3302 1675);
FORCEADD TAP..1
(-3300 1725);
FORCEPROP 3 LASTPIN (-3350 1725) SIG_NAME M_A_CPU1_SB_CB<6>
J 0
(-3340 1735);
DISPLAY 0.659574 (-3340 1735);
PAINT MONO (-3340 1735);
DISPLAY INVISIBLE (-3340 1735);
FORCEPROP 1 LASTPIN (-3350 1725) BN 6
J 0
(-3362 1733);
DISPLAY 0.489362 (-3362 1733);
PAINT GREEN (-3362 1733);
FORCEPROP 2 LAST CDS_LIB mstr_standard
J 2
(-3300 1725);
DISPLAY 0.723404 (-3300 1725);
PAINT MONO (-3300 1725);
DISPLAY INVISIBLE (-3300 1725);
FORCEPROP 1 LAST BODY_TYPE PLUMBING
J 0
(-3300 1775);
DISPLAY 0.872340 (-3300 1775);
PAINT GREEN (-3300 1775);
DISPLAY INVISIBLE (-3300 1775);
FORCEPROP 1 LAST HDL_TAP TRUE
J 0
(-2975 1600);
DISPLAY 0.872340 (-2975 1600);
DISPLAY INVISIBLE (-2975 1600);
FORCEPROP 1 LAST PATH I251
J 0
(-3302 1725);
DISPLAY 0.872340 (-3302 1725);
PAINT GREEN (-3302 1725);
DISPLAY INVISIBLE (-3302 1725);
FORCEADD TAP..1
R 2
(-5725 6075);
FORCEPROP 3 LASTPIN (-5675 6075) SIG_NAME M_A_CPU1_SA_DQS_DP<0>
J 0
(-5665 6085);
DISPLAY 0.659574 (-5665 6085);
PAINT MONO (-5665 6085);
DISPLAY INVISIBLE (-5665 6085);
FORCEPROP 1 LASTPIN (-5675 6075) BN 0
J 2
(-5663 6083);
DISPLAY 0.489362 (-5663 6083);
PAINT GREEN (-5663 6083);
FORCEPROP 2 LAST CDS_LIB mstr_standard
J 2
(-5725 6075);
DISPLAY 0.723404 (-5725 6075);
PAINT MONO (-5725 6075);
DISPLAY INVISIBLE (-5725 6075);
FORCEPROP 1 LAST BODY_TYPE PLUMBING
J 2
(-5725 6125);
DISPLAY 0.872340 (-5725 6125);
PAINT GREEN (-5725 6125);
DISPLAY INVISIBLE (-5725 6125);
FORCEPROP 1 LAST HDL_TAP TRUE
J 2
(-6050 5950);
DISPLAY 0.872340 (-6050 5950);
DISPLAY INVISIBLE (-6050 5950);
FORCEPROP 1 LAST PATH I252
J 2
(-5723 6075);
DISPLAY 0.872340 (-5723 6075);
PAINT GREEN (-5723 6075);
DISPLAY INVISIBLE (-5723 6075);
FORCEADD TAP..1
R 2
(-5725 5975);
FORCEPROP 3 LASTPIN (-5675 5975) SIG_NAME M_A_CPU1_SA_DQS_DP<1>
J 0
(-5665 5985);
DISPLAY 0.659574 (-5665 5985);
PAINT MONO (-5665 5985);
DISPLAY INVISIBLE (-5665 5985);
FORCEPROP 1 LASTPIN (-5675 5975) BN 1
J 2
(-5663 5983);
DISPLAY 0.489362 (-5663 5983);
PAINT GREEN (-5663 5983);
FORCEPROP 2 LAST CDS_LIB mstr_standard
J 2
(-5725 5975);
DISPLAY 0.723404 (-5725 5975);
PAINT MONO (-5725 5975);
DISPLAY INVISIBLE (-5725 5975);
FORCEPROP 1 LAST BODY_TYPE PLUMBING
J 2
(-5725 6025);
DISPLAY 0.872340 (-5725 6025);
PAINT GREEN (-5725 6025);
DISPLAY INVISIBLE (-5725 6025);
FORCEPROP 1 LAST HDL_TAP TRUE
J 2
(-6050 5850);
DISPLAY 0.872340 (-6050 5850);
DISPLAY INVISIBLE (-6050 5850);
FORCEPROP 1 LAST PATH I253
J 2
(-5723 5975);
DISPLAY 0.872340 (-5723 5975);
PAINT GREEN (-5723 5975);
DISPLAY INVISIBLE (-5723 5975);
FORCEADD TAP..1
R 2
(-5725 5875);
FORCEPROP 3 LASTPIN (-5675 5875) SIG_NAME M_A_CPU1_SA_DQS_DP<2>
J 0
(-5665 5885);
DISPLAY 0.659574 (-5665 5885);
PAINT MONO (-5665 5885);
DISPLAY INVISIBLE (-5665 5885);
FORCEPROP 1 LASTPIN (-5675 5875) BN 2
J 2
(-5663 5883);
DISPLAY 0.489362 (-5663 5883);
PAINT GREEN (-5663 5883);
FORCEPROP 2 LAST CDS_LIB mstr_standard
J 2
(-5725 5875);
DISPLAY 0.723404 (-5725 5875);
PAINT MONO (-5725 5875);
DISPLAY INVISIBLE (-5725 5875);
FORCEPROP 1 LAST BODY_TYPE PLUMBING
J 2
(-5725 5925);
DISPLAY 0.872340 (-5725 5925);
PAINT GREEN (-5725 5925);
DISPLAY INVISIBLE (-5725 5925);
FORCEPROP 1 LAST HDL_TAP TRUE
J 2
(-6050 5750);
DISPLAY 0.872340 (-6050 5750);
DISPLAY INVISIBLE (-6050 5750);
FORCEPROP 1 LAST PATH I254
J 2
(-5723 5875);
DISPLAY 0.872340 (-5723 5875);
PAINT GREEN (-5723 5875);
DISPLAY INVISIBLE (-5723 5875);
FORCEADD TAP..1
R 2
(-5925 6025);
FORCEPROP 3 LASTPIN (-5875 6025) SIG_NAME M_A_CPU1_SA_DQS_DN<0>
J 0
(-5865 6035);
DISPLAY 0.659574 (-5865 6035);
PAINT MONO (-5865 6035);
DISPLAY INVISIBLE (-5865 6035);
FORCEPROP 1 LASTPIN (-5875 6025) BN 0
J 2
(-5863 6033);
DISPLAY 0.489362 (-5863 6033);
PAINT GREEN (-5863 6033);
FORCEPROP 2 LAST CDS_LIB mstr_standard
J 2
(-5925 6025);
DISPLAY 0.723404 (-5925 6025);
PAINT MONO (-5925 6025);
DISPLAY INVISIBLE (-5925 6025);
FORCEPROP 1 LAST BODY_TYPE PLUMBING
J 2
(-5925 6075);
DISPLAY 0.872340 (-5925 6075);
PAINT GREEN (-5925 6075);
DISPLAY INVISIBLE (-5925 6075);
FORCEPROP 1 LAST HDL_TAP TRUE
J 2
(-6250 5900);
DISPLAY 0.872340 (-6250 5900);
DISPLAY INVISIBLE (-6250 5900);
FORCEPROP 1 LAST PATH I255
J 2
(-5923 6025);
DISPLAY 0.872340 (-5923 6025);
PAINT GREEN (-5923 6025);
DISPLAY INVISIBLE (-5923 6025);
FORCEADD TAP..1
R 2
(-5925 5925);
FORCEPROP 3 LASTPIN (-5875 5925) SIG_NAME M_A_CPU1_SA_DQS_DN<1>
J 0
(-5865 5935);
DISPLAY 0.659574 (-5865 5935);
PAINT MONO (-5865 5935);
DISPLAY INVISIBLE (-5865 5935);
FORCEPROP 1 LASTPIN (-5875 5925) BN 1
J 2
(-5863 5933);
DISPLAY 0.489362 (-5863 5933);
PAINT GREEN (-5863 5933);
FORCEPROP 2 LAST CDS_LIB mstr_standard
J 2
(-5925 5925);
DISPLAY 0.723404 (-5925 5925);
PAINT MONO (-5925 5925);
DISPLAY INVISIBLE (-5925 5925);
FORCEPROP 1 LAST BODY_TYPE PLUMBING
J 2
(-5925 5975);
DISPLAY 0.872340 (-5925 5975);
PAINT GREEN (-5925 5975);
DISPLAY INVISIBLE (-5925 5975);
FORCEPROP 1 LAST HDL_TAP TRUE
J 2
(-6250 5800);
DISPLAY 0.872340 (-6250 5800);
DISPLAY INVISIBLE (-6250 5800);
FORCEPROP 1 LAST PATH I256
J 2
(-5923 5925);
DISPLAY 0.872340 (-5923 5925);
PAINT GREEN (-5923 5925);
DISPLAY INVISIBLE (-5923 5925);
FORCEADD TAP..1
R 2
(-5725 5775);
FORCEPROP 3 LASTPIN (-5675 5775) SIG_NAME M_A_CPU1_SA_DQS_DP<3>
J 0
(-5665 5785);
DISPLAY 0.659574 (-5665 5785);
PAINT MONO (-5665 5785);
DISPLAY INVISIBLE (-5665 5785);
FORCEPROP 1 LASTPIN (-5675 5775) BN 3
J 2
(-5663 5783);
DISPLAY 0.489362 (-5663 5783);
PAINT GREEN (-5663 5783);
FORCEPROP 2 LAST CDS_LIB mstr_standard
J 2
(-5725 5775);
DISPLAY 0.723404 (-5725 5775);
PAINT MONO (-5725 5775);
DISPLAY INVISIBLE (-5725 5775);
FORCEPROP 1 LAST BODY_TYPE PLUMBING
J 2
(-5725 5825);
DISPLAY 0.872340 (-5725 5825);
PAINT GREEN (-5725 5825);
DISPLAY INVISIBLE (-5725 5825);
FORCEPROP 1 LAST HDL_TAP TRUE
J 2
(-6050 5650);
DISPLAY 0.872340 (-6050 5650);
DISPLAY INVISIBLE (-6050 5650);
FORCEPROP 1 LAST PATH I257
J 2
(-5723 5775);
DISPLAY 0.872340 (-5723 5775);
PAINT GREEN (-5723 5775);
DISPLAY INVISIBLE (-5723 5775);
FORCEADD TAP..1
R 2
(-5725 5675);
FORCEPROP 3 LASTPIN (-5675 5675) SIG_NAME M_A_CPU1_SA_DQS_DP<4>
J 0
(-5665 5685);
DISPLAY 0.659574 (-5665 5685);
PAINT MONO (-5665 5685);
DISPLAY INVISIBLE (-5665 5685);
FORCEPROP 1 LASTPIN (-5675 5675) BN 4
J 2
(-5663 5683);
DISPLAY 0.489362 (-5663 5683);
PAINT GREEN (-5663 5683);
FORCEPROP 2 LAST CDS_LIB mstr_standard
J 2
(-5725 5675);
DISPLAY 0.723404 (-5725 5675);
PAINT MONO (-5725 5675);
DISPLAY INVISIBLE (-5725 5675);
FORCEPROP 1 LAST BODY_TYPE PLUMBING
J 2
(-5725 5725);
DISPLAY 0.872340 (-5725 5725);
PAINT GREEN (-5725 5725);
DISPLAY INVISIBLE (-5725 5725);
FORCEPROP 1 LAST HDL_TAP TRUE
J 2
(-6050 5550);
DISPLAY 0.872340 (-6050 5550);
DISPLAY INVISIBLE (-6050 5550);
FORCEPROP 1 LAST PATH I258
J 2
(-5723 5675);
DISPLAY 0.872340 (-5723 5675);
PAINT GREEN (-5723 5675);
DISPLAY INVISIBLE (-5723 5675);
FORCEADD TAP..1
R 2
(-5925 5825);
FORCEPROP 3 LASTPIN (-5875 5825) SIG_NAME M_A_CPU1_SA_DQS_DN<2>
J 0
(-5865 5835);
DISPLAY 0.659574 (-5865 5835);
PAINT MONO (-5865 5835);
DISPLAY INVISIBLE (-5865 5835);
FORCEPROP 1 LASTPIN (-5875 5825) BN 2
J 2
(-5863 5833);
DISPLAY 0.489362 (-5863 5833);
PAINT GREEN (-5863 5833);
FORCEPROP 2 LAST CDS_LIB mstr_standard
J 2
(-5925 5825);
DISPLAY 0.723404 (-5925 5825);
PAINT MONO (-5925 5825);
DISPLAY INVISIBLE (-5925 5825);
FORCEPROP 1 LAST BODY_TYPE PLUMBING
J 2
(-5925 5875);
DISPLAY 0.872340 (-5925 5875);
PAINT GREEN (-5925 5875);
DISPLAY INVISIBLE (-5925 5875);
FORCEPROP 1 LAST HDL_TAP TRUE
J 2
(-6250 5700);
DISPLAY 0.872340 (-6250 5700);
DISPLAY INVISIBLE (-6250 5700);
FORCEPROP 1 LAST PATH I259
J 2
(-5923 5825);
DISPLAY 0.872340 (-5923 5825);
PAINT GREEN (-5923 5825);
DISPLAY INVISIBLE (-5923 5825);
FORCEADD TAP..1
R 2
(-5925 5725);
FORCEPROP 3 LASTPIN (-5875 5725) SIG_NAME M_A_CPU1_SA_DQS_DN<3>
J 0
(-5865 5735);
DISPLAY 0.659574 (-5865 5735);
PAINT MONO (-5865 5735);
DISPLAY INVISIBLE (-5865 5735);
FORCEPROP 1 LASTPIN (-5875 5725) BN 3
J 2
(-5863 5733);
DISPLAY 0.489362 (-5863 5733);
PAINT GREEN (-5863 5733);
FORCEPROP 2 LAST CDS_LIB mstr_standard
J 2
(-5925 5725);
DISPLAY 0.723404 (-5925 5725);
PAINT MONO (-5925 5725);
DISPLAY INVISIBLE (-5925 5725);
FORCEPROP 1 LAST BODY_TYPE PLUMBING
J 2
(-5925 5775);
DISPLAY 0.872340 (-5925 5775);
PAINT GREEN (-5925 5775);
DISPLAY INVISIBLE (-5925 5775);
FORCEPROP 1 LAST HDL_TAP TRUE
J 2
(-6250 5600);
DISPLAY 0.872340 (-6250 5600);
DISPLAY INVISIBLE (-6250 5600);
FORCEPROP 1 LAST PATH I260
J 2
(-5923 5725);
DISPLAY 0.872340 (-5923 5725);
PAINT GREEN (-5923 5725);
DISPLAY INVISIBLE (-5923 5725);
FORCEADD TAP..1
R 2
(-5725 5575);
FORCEPROP 3 LASTPIN (-5675 5575) SIG_NAME M_A_CPU1_SA_DQS_DP<5>
J 0
(-5665 5585);
DISPLAY 0.659574 (-5665 5585);
PAINT MONO (-5665 5585);
DISPLAY INVISIBLE (-5665 5585);
FORCEPROP 1 LASTPIN (-5675 5575) BN 5
J 2
(-5663 5583);
DISPLAY 0.489362 (-5663 5583);
PAINT GREEN (-5663 5583);
FORCEPROP 2 LAST CDS_LIB mstr_standard
J 2
(-5725 5575);
DISPLAY 0.723404 (-5725 5575);
PAINT MONO (-5725 5575);
DISPLAY INVISIBLE (-5725 5575);
FORCEPROP 1 LAST BODY_TYPE PLUMBING
J 2
(-5725 5625);
DISPLAY 0.872340 (-5725 5625);
PAINT GREEN (-5725 5625);
DISPLAY INVISIBLE (-5725 5625);
FORCEPROP 1 LAST HDL_TAP TRUE
J 2
(-6050 5450);
DISPLAY 0.872340 (-6050 5450);
DISPLAY INVISIBLE (-6050 5450);
FORCEPROP 1 LAST PATH I261
J 2
(-5723 5575);
DISPLAY 0.872340 (-5723 5575);
PAINT GREEN (-5723 5575);
DISPLAY INVISIBLE (-5723 5575);
FORCEADD TAP..1
R 2
(-5725 5375);
FORCEPROP 3 LASTPIN (-5675 5375) SIG_NAME M_A_CPU1_SA_DQS_DP<7>
J 0
(-5665 5385);
DISPLAY 0.659574 (-5665 5385);
PAINT MONO (-5665 5385);
DISPLAY INVISIBLE (-5665 5385);
FORCEPROP 1 LASTPIN (-5675 5375) BN 7
J 2
(-5663 5383);
DISPLAY 0.489362 (-5663 5383);
PAINT GREEN (-5663 5383);
FORCEPROP 2 LAST CDS_LIB mstr_standard
J 2
(-5725 5375);
DISPLAY 0.723404 (-5725 5375);
PAINT MONO (-5725 5375);
DISPLAY INVISIBLE (-5725 5375);
FORCEPROP 1 LAST BODY_TYPE PLUMBING
J 2
(-5725 5425);
DISPLAY 0.872340 (-5725 5425);
PAINT GREEN (-5725 5425);
DISPLAY INVISIBLE (-5725 5425);
FORCEPROP 1 LAST HDL_TAP TRUE
J 2
(-6050 5250);
DISPLAY 0.872340 (-6050 5250);
DISPLAY INVISIBLE (-6050 5250);
FORCEPROP 1 LAST PATH I262
J 2
(-5723 5375);
DISPLAY 0.872340 (-5723 5375);
PAINT GREEN (-5723 5375);
DISPLAY INVISIBLE (-5723 5375);
FORCEADD TAP..1
R 2
(-5725 5475);
FORCEPROP 3 LASTPIN (-5675 5475) SIG_NAME M_A_CPU1_SA_DQS_DP<6>
J 0
(-5665 5485);
DISPLAY 0.659574 (-5665 5485);
PAINT MONO (-5665 5485);
DISPLAY INVISIBLE (-5665 5485);
FORCEPROP 1 LASTPIN (-5675 5475) BN 6
J 2
(-5663 5483);
DISPLAY 0.489362 (-5663 5483);
PAINT GREEN (-5663 5483);
FORCEPROP 2 LAST CDS_LIB mstr_standard
J 2
(-5725 5475);
DISPLAY 0.723404 (-5725 5475);
PAINT MONO (-5725 5475);
DISPLAY INVISIBLE (-5725 5475);
FORCEPROP 1 LAST BODY_TYPE PLUMBING
J 2
(-5725 5525);
DISPLAY 0.872340 (-5725 5525);
PAINT GREEN (-5725 5525);
DISPLAY INVISIBLE (-5725 5525);
FORCEPROP 1 LAST HDL_TAP TRUE
J 2
(-6050 5350);
DISPLAY 0.872340 (-6050 5350);
DISPLAY INVISIBLE (-6050 5350);
FORCEPROP 1 LAST PATH I263
J 2
(-5723 5475);
DISPLAY 0.872340 (-5723 5475);
PAINT GREEN (-5723 5475);
DISPLAY INVISIBLE (-5723 5475);
FORCEADD TAP..1
R 2
(-5925 5625);
FORCEPROP 3 LASTPIN (-5875 5625) SIG_NAME M_A_CPU1_SA_DQS_DN<4>
J 0
(-5865 5635);
DISPLAY 0.659574 (-5865 5635);
PAINT MONO (-5865 5635);
DISPLAY INVISIBLE (-5865 5635);
FORCEPROP 1 LASTPIN (-5875 5625) BN 4
J 2
(-5863 5633);
DISPLAY 0.489362 (-5863 5633);
PAINT GREEN (-5863 5633);
FORCEPROP 2 LAST CDS_LIB mstr_standard
J 2
(-5925 5625);
DISPLAY 0.723404 (-5925 5625);
PAINT MONO (-5925 5625);
DISPLAY INVISIBLE (-5925 5625);
FORCEPROP 1 LAST BODY_TYPE PLUMBING
J 2
(-5925 5675);
DISPLAY 0.872340 (-5925 5675);
PAINT GREEN (-5925 5675);
DISPLAY INVISIBLE (-5925 5675);
FORCEPROP 1 LAST HDL_TAP TRUE
J 2
(-6250 5500);
DISPLAY 0.872340 (-6250 5500);
DISPLAY INVISIBLE (-6250 5500);
FORCEPROP 1 LAST PATH I264
J 2
(-5923 5625);
DISPLAY 0.872340 (-5923 5625);
PAINT GREEN (-5923 5625);
DISPLAY INVISIBLE (-5923 5625);
FORCEADD TAP..1
R 2
(-5925 5525);
FORCEPROP 3 LASTPIN (-5875 5525) SIG_NAME M_A_CPU1_SA_DQS_DN<5>
J 0
(-5865 5535);
DISPLAY 0.659574 (-5865 5535);
PAINT MONO (-5865 5535);
DISPLAY INVISIBLE (-5865 5535);
FORCEPROP 1 LASTPIN (-5875 5525) BN 5
J 2
(-5863 5533);
DISPLAY 0.489362 (-5863 5533);
PAINT GREEN (-5863 5533);
FORCEPROP 2 LAST CDS_LIB mstr_standard
J 2
(-5925 5525);
DISPLAY 0.723404 (-5925 5525);
PAINT MONO (-5925 5525);
DISPLAY INVISIBLE (-5925 5525);
FORCEPROP 1 LAST BODY_TYPE PLUMBING
J 2
(-5925 5575);
DISPLAY 0.872340 (-5925 5575);
PAINT GREEN (-5925 5575);
DISPLAY INVISIBLE (-5925 5575);
FORCEPROP 1 LAST HDL_TAP TRUE
J 2
(-6250 5400);
DISPLAY 0.872340 (-6250 5400);
DISPLAY INVISIBLE (-6250 5400);
FORCEPROP 1 LAST PATH I265
J 2
(-5923 5525);
DISPLAY 0.872340 (-5923 5525);
PAINT GREEN (-5923 5525);
DISPLAY INVISIBLE (-5923 5525);
FORCEADD TAP..1
R 2
(-5925 5425);
FORCEPROP 3 LASTPIN (-5875 5425) SIG_NAME M_A_CPU1_SA_DQS_DN<6>
J 0
(-5865 5435);
DISPLAY 0.659574 (-5865 5435);
PAINT MONO (-5865 5435);
DISPLAY INVISIBLE (-5865 5435);
FORCEPROP 1 LASTPIN (-5875 5425) BN 6
J 2
(-5863 5433);
DISPLAY 0.489362 (-5863 5433);
PAINT GREEN (-5863 5433);
FORCEPROP 2 LAST CDS_LIB mstr_standard
J 2
(-5925 5425);
DISPLAY 0.723404 (-5925 5425);
PAINT MONO (-5925 5425);
DISPLAY INVISIBLE (-5925 5425);
FORCEPROP 1 LAST BODY_TYPE PLUMBING
J 2
(-5925 5475);
DISPLAY 0.872340 (-5925 5475);
PAINT GREEN (-5925 5475);
DISPLAY INVISIBLE (-5925 5475);
FORCEPROP 1 LAST HDL_TAP TRUE
J 2
(-6250 5300);
DISPLAY 0.872340 (-6250 5300);
DISPLAY INVISIBLE (-6250 5300);
FORCEPROP 1 LAST PATH I266
J 2
(-5923 5425);
DISPLAY 0.872340 (-5923 5425);
PAINT GREEN (-5923 5425);
DISPLAY INVISIBLE (-5923 5425);
FORCEADD TAP..1
R 2
(-5725 5275);
FORCEPROP 3 LASTPIN (-5675 5275) SIG_NAME M_A_CPU1_SA_DQS_DP<8>
J 0
(-5665 5285);
DISPLAY 0.659574 (-5665 5285);
PAINT MONO (-5665 5285);
DISPLAY INVISIBLE (-5665 5285);
FORCEPROP 1 LASTPIN (-5675 5275) BN 8
J 2
(-5663 5283);
DISPLAY 0.489362 (-5663 5283);
PAINT GREEN (-5663 5283);
FORCEPROP 2 LAST CDS_LIB mstr_standard
J 2
(-5725 5275);
DISPLAY 0.723404 (-5725 5275);
PAINT MONO (-5725 5275);
DISPLAY INVISIBLE (-5725 5275);
FORCEPROP 1 LAST BODY_TYPE PLUMBING
J 2
(-5725 5325);
DISPLAY 0.872340 (-5725 5325);
PAINT GREEN (-5725 5325);
DISPLAY INVISIBLE (-5725 5325);
FORCEPROP 1 LAST HDL_TAP TRUE
J 2
(-6050 5150);
DISPLAY 0.872340 (-6050 5150);
DISPLAY INVISIBLE (-6050 5150);
FORCEPROP 1 LAST PATH I267
J 2
(-5723 5275);
DISPLAY 0.872340 (-5723 5275);
PAINT GREEN (-5723 5275);
DISPLAY INVISIBLE (-5723 5275);
FORCEADD TAP..1
R 2
(-5725 5175);
FORCEPROP 3 LASTPIN (-5675 5175) SIG_NAME M_A_CPU1_SA_DQS_DP<9>
J 0
(-5665 5185);
DISPLAY 0.659574 (-5665 5185);
PAINT MONO (-5665 5185);
DISPLAY INVISIBLE (-5665 5185);
FORCEPROP 1 LASTPIN (-5675 5175) BN 9
J 2
(-5663 5183);
DISPLAY 0.489362 (-5663 5183);
PAINT GREEN (-5663 5183);
FORCEPROP 2 LAST CDS_LIB mstr_standard
J 2
(-5725 5175);
DISPLAY 0.723404 (-5725 5175);
PAINT MONO (-5725 5175);
DISPLAY INVISIBLE (-5725 5175);
FORCEPROP 1 LAST BODY_TYPE PLUMBING
J 2
(-5725 5225);
DISPLAY 0.872340 (-5725 5225);
PAINT GREEN (-5725 5225);
DISPLAY INVISIBLE (-5725 5225);
FORCEPROP 1 LAST HDL_TAP TRUE
J 2
(-6050 5050);
DISPLAY 0.872340 (-6050 5050);
DISPLAY INVISIBLE (-6050 5050);
FORCEPROP 1 LAST PATH I268
J 2
(-5723 5175);
DISPLAY 0.872340 (-5723 5175);
PAINT GREEN (-5723 5175);
DISPLAY INVISIBLE (-5723 5175);
FORCEADD TAP..1
R 2
(-5925 5325);
FORCEPROP 3 LASTPIN (-5875 5325) SIG_NAME M_A_CPU1_SA_DQS_DN<7>
J 0
(-5865 5335);
DISPLAY 0.659574 (-5865 5335);
PAINT MONO (-5865 5335);
DISPLAY INVISIBLE (-5865 5335);
FORCEPROP 1 LASTPIN (-5875 5325) BN 7
J 2
(-5863 5333);
DISPLAY 0.489362 (-5863 5333);
PAINT GREEN (-5863 5333);
FORCEPROP 2 LAST CDS_LIB mstr_standard
J 2
(-5925 5325);
DISPLAY 0.723404 (-5925 5325);
PAINT MONO (-5925 5325);
DISPLAY INVISIBLE (-5925 5325);
FORCEPROP 1 LAST BODY_TYPE PLUMBING
J 2
(-5925 5375);
DISPLAY 0.872340 (-5925 5375);
PAINT GREEN (-5925 5375);
DISPLAY INVISIBLE (-5925 5375);
FORCEPROP 1 LAST HDL_TAP TRUE
J 2
(-6250 5200);
DISPLAY 0.872340 (-6250 5200);
DISPLAY INVISIBLE (-6250 5200);
FORCEPROP 1 LAST PATH I269
J 2
(-5923 5325);
DISPLAY 0.872340 (-5923 5325);
PAINT GREEN (-5923 5325);
DISPLAY INVISIBLE (-5923 5325);
FORCEADD TAP..1
R 2
(-5925 5225);
FORCEPROP 3 LASTPIN (-5875 5225) SIG_NAME M_A_CPU1_SA_DQS_DN<8>
J 0
(-5865 5235);
DISPLAY 0.659574 (-5865 5235);
PAINT MONO (-5865 5235);
DISPLAY INVISIBLE (-5865 5235);
FORCEPROP 1 LASTPIN (-5875 5225) BN 8
J 2
(-5863 5233);
DISPLAY 0.489362 (-5863 5233);
PAINT GREEN (-5863 5233);
FORCEPROP 2 LAST CDS_LIB mstr_standard
J 2
(-5925 5225);
DISPLAY 0.723404 (-5925 5225);
PAINT MONO (-5925 5225);
DISPLAY INVISIBLE (-5925 5225);
FORCEPROP 1 LAST BODY_TYPE PLUMBING
J 2
(-5925 5275);
DISPLAY 0.872340 (-5925 5275);
PAINT GREEN (-5925 5275);
DISPLAY INVISIBLE (-5925 5275);
FORCEPROP 1 LAST HDL_TAP TRUE
J 2
(-6250 5100);
DISPLAY 0.872340 (-6250 5100);
DISPLAY INVISIBLE (-6250 5100);
FORCEPROP 1 LAST PATH I270
J 2
(-5923 5225);
DISPLAY 0.872340 (-5923 5225);
PAINT GREEN (-5923 5225);
DISPLAY INVISIBLE (-5923 5225);
FORCEADD TAP..1
R 2
(-5925 5125);
FORCEPROP 3 LASTPIN (-5875 5125) SIG_NAME M_A_CPU1_SA_DQS_DN<9>
J 0
(-5865 5135);
DISPLAY 0.659574 (-5865 5135);
PAINT MONO (-5865 5135);
DISPLAY INVISIBLE (-5865 5135);
FORCEPROP 1 LASTPIN (-5875 5125) BN 9
J 2
(-5863 5133);
DISPLAY 0.489362 (-5863 5133);
PAINT GREEN (-5863 5133);
FORCEPROP 2 LAST CDS_LIB mstr_standard
J 2
(-5925 5125);
DISPLAY 0.723404 (-5925 5125);
PAINT MONO (-5925 5125);
DISPLAY INVISIBLE (-5925 5125);
FORCEPROP 1 LAST BODY_TYPE PLUMBING
J 2
(-5925 5175);
DISPLAY 0.872340 (-5925 5175);
PAINT GREEN (-5925 5175);
DISPLAY INVISIBLE (-5925 5175);
FORCEPROP 1 LAST HDL_TAP TRUE
J 2
(-6250 5000);
DISPLAY 0.872340 (-6250 5000);
DISPLAY INVISIBLE (-6250 5000);
FORCEPROP 1 LAST PATH I271
J 2
(-5923 5125);
DISPLAY 0.872340 (-5923 5125);
PAINT GREEN (-5923 5125);
DISPLAY INVISIBLE (-5923 5125);
FORCEADD TAP..1
R 2
(-5725 5025);
FORCEPROP 3 LASTPIN (-5675 5025) SIG_NAME M_A_CPU1_SB_DQS_DP<0>
J 0
(-5665 5035);
DISPLAY 0.659574 (-5665 5035);
PAINT MONO (-5665 5035);
DISPLAY INVISIBLE (-5665 5035);
FORCEPROP 1 LASTPIN (-5675 5025) BN 0
J 2
(-5663 5033);
DISPLAY 0.489362 (-5663 5033);
PAINT GREEN (-5663 5033);
FORCEPROP 2 LAST CDS_LIB mstr_standard
J 2
(-5725 5025);
DISPLAY 0.723404 (-5725 5025);
PAINT MONO (-5725 5025);
DISPLAY INVISIBLE (-5725 5025);
FORCEPROP 1 LAST BODY_TYPE PLUMBING
J 2
(-5725 5075);
DISPLAY 0.872340 (-5725 5075);
PAINT GREEN (-5725 5075);
DISPLAY INVISIBLE (-5725 5075);
FORCEPROP 1 LAST HDL_TAP TRUE
J 2
(-6050 4900);
DISPLAY 0.872340 (-6050 4900);
DISPLAY INVISIBLE (-6050 4900);
FORCEPROP 1 LAST PATH I272
J 2
(-5723 5025);
DISPLAY 0.872340 (-5723 5025);
PAINT GREEN (-5723 5025);
DISPLAY INVISIBLE (-5723 5025);
FORCEADD TAP..1
R 2
(-5725 4925);
FORCEPROP 3 LASTPIN (-5675 4925) SIG_NAME M_A_CPU1_SB_DQS_DP<1>
J 0
(-5665 4935);
DISPLAY 0.659574 (-5665 4935);
PAINT MONO (-5665 4935);
DISPLAY INVISIBLE (-5665 4935);
FORCEPROP 1 LASTPIN (-5675 4925) BN 1
J 2
(-5663 4933);
DISPLAY 0.489362 (-5663 4933);
PAINT GREEN (-5663 4933);
FORCEPROP 2 LAST CDS_LIB mstr_standard
J 2
(-5725 4925);
DISPLAY 0.723404 (-5725 4925);
PAINT MONO (-5725 4925);
DISPLAY INVISIBLE (-5725 4925);
FORCEPROP 1 LAST BODY_TYPE PLUMBING
J 2
(-5725 4975);
DISPLAY 0.872340 (-5725 4975);
PAINT GREEN (-5725 4975);
DISPLAY INVISIBLE (-5725 4975);
FORCEPROP 1 LAST HDL_TAP TRUE
J 2
(-6050 4800);
DISPLAY 0.872340 (-6050 4800);
DISPLAY INVISIBLE (-6050 4800);
FORCEPROP 1 LAST PATH I273
J 2
(-5723 4925);
DISPLAY 0.872340 (-5723 4925);
PAINT GREEN (-5723 4925);
DISPLAY INVISIBLE (-5723 4925);
FORCEADD TAP..1
R 2
(-5925 4975);
FORCEPROP 3 LASTPIN (-5875 4975) SIG_NAME M_A_CPU1_SB_DQS_DN<0>
J 0
(-5865 4985);
DISPLAY 0.659574 (-5865 4985);
PAINT MONO (-5865 4985);
DISPLAY INVISIBLE (-5865 4985);
FORCEPROP 1 LASTPIN (-5875 4975) BN 0
J 2
(-5863 4983);
DISPLAY 0.489362 (-5863 4983);
PAINT GREEN (-5863 4983);
FORCEPROP 2 LAST CDS_LIB mstr_standard
J 2
(-5925 4975);
DISPLAY 0.723404 (-5925 4975);
PAINT MONO (-5925 4975);
DISPLAY INVISIBLE (-5925 4975);
FORCEPROP 1 LAST BODY_TYPE PLUMBING
J 2
(-5925 5025);
DISPLAY 0.872340 (-5925 5025);
PAINT GREEN (-5925 5025);
DISPLAY INVISIBLE (-5925 5025);
FORCEPROP 1 LAST HDL_TAP TRUE
J 2
(-6250 4850);
DISPLAY 0.872340 (-6250 4850);
DISPLAY INVISIBLE (-6250 4850);
FORCEPROP 1 LAST PATH I274
J 2
(-5923 4975);
DISPLAY 0.872340 (-5923 4975);
PAINT GREEN (-5923 4975);
DISPLAY INVISIBLE (-5923 4975);
FORCEADD TAP..1
R 2
(-5925 4875);
FORCEPROP 3 LASTPIN (-5875 4875) SIG_NAME M_A_CPU1_SB_DQS_DN<1>
J 0
(-5865 4885);
DISPLAY 0.659574 (-5865 4885);
PAINT MONO (-5865 4885);
DISPLAY INVISIBLE (-5865 4885);
FORCEPROP 1 LASTPIN (-5875 4875) BN 1
J 2
(-5863 4883);
DISPLAY 0.489362 (-5863 4883);
PAINT GREEN (-5863 4883);
FORCEPROP 2 LAST CDS_LIB mstr_standard
J 2
(-5925 4875);
DISPLAY 0.723404 (-5925 4875);
PAINT MONO (-5925 4875);
DISPLAY INVISIBLE (-5925 4875);
FORCEPROP 1 LAST BODY_TYPE PLUMBING
J 2
(-5925 4925);
DISPLAY 0.872340 (-5925 4925);
PAINT GREEN (-5925 4925);
DISPLAY INVISIBLE (-5925 4925);
FORCEPROP 1 LAST HDL_TAP TRUE
J 2
(-6250 4750);
DISPLAY 0.872340 (-6250 4750);
DISPLAY INVISIBLE (-6250 4750);
FORCEPROP 1 LAST PATH I275
J 2
(-5923 4875);
DISPLAY 0.872340 (-5923 4875);
PAINT GREEN (-5923 4875);
DISPLAY INVISIBLE (-5923 4875);
FORCEADD TAP..1
R 2
(-5725 4825);
FORCEPROP 3 LASTPIN (-5675 4825) SIG_NAME M_A_CPU1_SB_DQS_DP<2>
J 0
(-5665 4835);
DISPLAY 0.659574 (-5665 4835);
PAINT MONO (-5665 4835);
DISPLAY INVISIBLE (-5665 4835);
FORCEPROP 1 LASTPIN (-5675 4825) BN 2
J 2
(-5663 4833);
DISPLAY 0.489362 (-5663 4833);
PAINT GREEN (-5663 4833);
FORCEPROP 2 LAST CDS_LIB mstr_standard
J 2
(-5725 4825);
DISPLAY 0.723404 (-5725 4825);
PAINT MONO (-5725 4825);
DISPLAY INVISIBLE (-5725 4825);
FORCEPROP 1 LAST BODY_TYPE PLUMBING
J 2
(-5725 4875);
DISPLAY 0.872340 (-5725 4875);
PAINT GREEN (-5725 4875);
DISPLAY INVISIBLE (-5725 4875);
FORCEPROP 1 LAST HDL_TAP TRUE
J 2
(-6050 4700);
DISPLAY 0.872340 (-6050 4700);
DISPLAY INVISIBLE (-6050 4700);
FORCEPROP 1 LAST PATH I276
J 2
(-5723 4825);
DISPLAY 0.872340 (-5723 4825);
PAINT GREEN (-5723 4825);
DISPLAY INVISIBLE (-5723 4825);
FORCEADD TAP..1
R 2
(-5725 4725);
FORCEPROP 3 LASTPIN (-5675 4725) SIG_NAME M_A_CPU1_SB_DQS_DP<3>
J 0
(-5665 4735);
DISPLAY 0.659574 (-5665 4735);
PAINT MONO (-5665 4735);
DISPLAY INVISIBLE (-5665 4735);
FORCEPROP 1 LASTPIN (-5675 4725) BN 3
J 2
(-5663 4733);
DISPLAY 0.489362 (-5663 4733);
PAINT GREEN (-5663 4733);
FORCEPROP 2 LAST CDS_LIB mstr_standard
J 2
(-5725 4725);
DISPLAY 0.723404 (-5725 4725);
PAINT MONO (-5725 4725);
DISPLAY INVISIBLE (-5725 4725);
FORCEPROP 1 LAST BODY_TYPE PLUMBING
J 2
(-5725 4775);
DISPLAY 0.872340 (-5725 4775);
PAINT GREEN (-5725 4775);
DISPLAY INVISIBLE (-5725 4775);
FORCEPROP 1 LAST HDL_TAP TRUE
J 2
(-6050 4600);
DISPLAY 0.872340 (-6050 4600);
DISPLAY INVISIBLE (-6050 4600);
FORCEPROP 1 LAST PATH I277
J 2
(-5723 4725);
DISPLAY 0.872340 (-5723 4725);
PAINT GREEN (-5723 4725);
DISPLAY INVISIBLE (-5723 4725);
FORCEADD TAP..1
R 2
(-5725 4625);
FORCEPROP 3 LASTPIN (-5675 4625) SIG_NAME M_A_CPU1_SB_DQS_DP<4>
J 0
(-5665 4635);
DISPLAY 0.659574 (-5665 4635);
PAINT MONO (-5665 4635);
DISPLAY INVISIBLE (-5665 4635);
FORCEPROP 1 LASTPIN (-5675 4625) BN 4
J 2
(-5663 4633);
DISPLAY 0.489362 (-5663 4633);
PAINT GREEN (-5663 4633);
FORCEPROP 2 LAST CDS_LIB mstr_standard
J 2
(-5725 4625);
DISPLAY 0.723404 (-5725 4625);
PAINT MONO (-5725 4625);
DISPLAY INVISIBLE (-5725 4625);
FORCEPROP 1 LAST BODY_TYPE PLUMBING
J 2
(-5725 4675);
DISPLAY 0.872340 (-5725 4675);
PAINT GREEN (-5725 4675);
DISPLAY INVISIBLE (-5725 4675);
FORCEPROP 1 LAST HDL_TAP TRUE
J 2
(-6050 4500);
DISPLAY 0.872340 (-6050 4500);
DISPLAY INVISIBLE (-6050 4500);
FORCEPROP 1 LAST PATH I278
J 2
(-5723 4625);
DISPLAY 0.872340 (-5723 4625);
PAINT GREEN (-5723 4625);
DISPLAY INVISIBLE (-5723 4625);
FORCEADD TAP..1
R 2
(-5925 4775);
FORCEPROP 3 LASTPIN (-5875 4775) SIG_NAME M_A_CPU1_SB_DQS_DN<2>
J 0
(-5865 4785);
DISPLAY 0.659574 (-5865 4785);
PAINT MONO (-5865 4785);
DISPLAY INVISIBLE (-5865 4785);
FORCEPROP 1 LASTPIN (-5875 4775) BN 2
J 2
(-5863 4783);
DISPLAY 0.489362 (-5863 4783);
PAINT GREEN (-5863 4783);
FORCEPROP 2 LAST CDS_LIB mstr_standard
J 2
(-5925 4775);
DISPLAY 0.723404 (-5925 4775);
PAINT MONO (-5925 4775);
DISPLAY INVISIBLE (-5925 4775);
FORCEPROP 1 LAST BODY_TYPE PLUMBING
J 2
(-5925 4825);
DISPLAY 0.872340 (-5925 4825);
PAINT GREEN (-5925 4825);
DISPLAY INVISIBLE (-5925 4825);
FORCEPROP 1 LAST HDL_TAP TRUE
J 2
(-6250 4650);
DISPLAY 0.872340 (-6250 4650);
DISPLAY INVISIBLE (-6250 4650);
FORCEPROP 1 LAST PATH I279
J 2
(-5923 4775);
DISPLAY 0.872340 (-5923 4775);
PAINT GREEN (-5923 4775);
DISPLAY INVISIBLE (-5923 4775);
FORCEADD TAP..1
R 2
(-5925 4675);
FORCEPROP 3 LASTPIN (-5875 4675) SIG_NAME M_A_CPU1_SB_DQS_DN<3>
J 0
(-5865 4685);
DISPLAY 0.659574 (-5865 4685);
PAINT MONO (-5865 4685);
DISPLAY INVISIBLE (-5865 4685);
FORCEPROP 1 LASTPIN (-5875 4675) BN 3
J 2
(-5863 4683);
DISPLAY 0.489362 (-5863 4683);
PAINT GREEN (-5863 4683);
FORCEPROP 2 LAST CDS_LIB mstr_standard
J 2
(-5925 4675);
DISPLAY 0.723404 (-5925 4675);
PAINT MONO (-5925 4675);
DISPLAY INVISIBLE (-5925 4675);
FORCEPROP 1 LAST BODY_TYPE PLUMBING
J 2
(-5925 4725);
DISPLAY 0.872340 (-5925 4725);
PAINT GREEN (-5925 4725);
DISPLAY INVISIBLE (-5925 4725);
FORCEPROP 1 LAST HDL_TAP TRUE
J 2
(-6250 4550);
DISPLAY 0.872340 (-6250 4550);
DISPLAY INVISIBLE (-6250 4550);
FORCEPROP 1 LAST PATH I280
J 2
(-5923 4675);
DISPLAY 0.872340 (-5923 4675);
PAINT GREEN (-5923 4675);
DISPLAY INVISIBLE (-5923 4675);
FORCEADD TAP..1
R 2
(-5725 4525);
FORCEPROP 3 LASTPIN (-5675 4525) SIG_NAME M_A_CPU1_SB_DQS_DP<5>
J 0
(-5665 4535);
DISPLAY 0.659574 (-5665 4535);
PAINT MONO (-5665 4535);
DISPLAY INVISIBLE (-5665 4535);
FORCEPROP 1 LASTPIN (-5675 4525) BN 5
J 2
(-5663 4533);
DISPLAY 0.489362 (-5663 4533);
PAINT GREEN (-5663 4533);
FORCEPROP 2 LAST CDS_LIB mstr_standard
J 2
(-5725 4525);
DISPLAY 0.723404 (-5725 4525);
PAINT MONO (-5725 4525);
DISPLAY INVISIBLE (-5725 4525);
FORCEPROP 1 LAST BODY_TYPE PLUMBING
J 2
(-5725 4575);
DISPLAY 0.872340 (-5725 4575);
PAINT GREEN (-5725 4575);
DISPLAY INVISIBLE (-5725 4575);
FORCEPROP 1 LAST HDL_TAP TRUE
J 2
(-6050 4400);
DISPLAY 0.872340 (-6050 4400);
DISPLAY INVISIBLE (-6050 4400);
FORCEPROP 1 LAST PATH I281
J 2
(-5723 4525);
DISPLAY 0.872340 (-5723 4525);
PAINT GREEN (-5723 4525);
DISPLAY INVISIBLE (-5723 4525);
FORCEADD TAP..1
R 2
(-5725 4425);
FORCEPROP 3 LASTPIN (-5675 4425) SIG_NAME M_A_CPU1_SB_DQS_DP<6>
J 0
(-5665 4435);
DISPLAY 0.659574 (-5665 4435);
PAINT MONO (-5665 4435);
DISPLAY INVISIBLE (-5665 4435);
FORCEPROP 1 LASTPIN (-5675 4425) BN 6
J 2
(-5663 4433);
DISPLAY 0.489362 (-5663 4433);
PAINT GREEN (-5663 4433);
FORCEPROP 2 LAST CDS_LIB mstr_standard
J 2
(-5725 4425);
DISPLAY 0.723404 (-5725 4425);
PAINT MONO (-5725 4425);
DISPLAY INVISIBLE (-5725 4425);
FORCEPROP 1 LAST BODY_TYPE PLUMBING
J 2
(-5725 4475);
DISPLAY 0.872340 (-5725 4475);
PAINT GREEN (-5725 4475);
DISPLAY INVISIBLE (-5725 4475);
FORCEPROP 1 LAST HDL_TAP TRUE
J 2
(-6050 4300);
DISPLAY 0.872340 (-6050 4300);
DISPLAY INVISIBLE (-6050 4300);
FORCEPROP 1 LAST PATH I282
J 2
(-5723 4425);
DISPLAY 0.872340 (-5723 4425);
PAINT GREEN (-5723 4425);
DISPLAY INVISIBLE (-5723 4425);
FORCEADD TAP..1
R 2
(-5925 4575);
FORCEPROP 3 LASTPIN (-5875 4575) SIG_NAME M_A_CPU1_SB_DQS_DN<4>
J 0
(-5865 4585);
DISPLAY 0.659574 (-5865 4585);
PAINT MONO (-5865 4585);
DISPLAY INVISIBLE (-5865 4585);
FORCEPROP 1 LASTPIN (-5875 4575) BN 4
J 2
(-5863 4583);
DISPLAY 0.489362 (-5863 4583);
PAINT GREEN (-5863 4583);
FORCEPROP 2 LAST CDS_LIB mstr_standard
J 2
(-5925 4575);
DISPLAY 0.723404 (-5925 4575);
PAINT MONO (-5925 4575);
DISPLAY INVISIBLE (-5925 4575);
FORCEPROP 1 LAST BODY_TYPE PLUMBING
J 2
(-5925 4625);
DISPLAY 0.872340 (-5925 4625);
PAINT GREEN (-5925 4625);
DISPLAY INVISIBLE (-5925 4625);
FORCEPROP 1 LAST HDL_TAP TRUE
J 2
(-6250 4450);
DISPLAY 0.872340 (-6250 4450);
DISPLAY INVISIBLE (-6250 4450);
FORCEPROP 1 LAST PATH I283
J 2
(-5923 4575);
DISPLAY 0.872340 (-5923 4575);
PAINT GREEN (-5923 4575);
DISPLAY INVISIBLE (-5923 4575);
FORCEADD TAP..1
R 2
(-5925 4475);
FORCEPROP 3 LASTPIN (-5875 4475) SIG_NAME M_A_CPU1_SB_DQS_DN<5>
J 0
(-5865 4485);
DISPLAY 0.659574 (-5865 4485);
PAINT MONO (-5865 4485);
DISPLAY INVISIBLE (-5865 4485);
FORCEPROP 1 LASTPIN (-5875 4475) BN 5
J 2
(-5863 4483);
DISPLAY 0.489362 (-5863 4483);
PAINT GREEN (-5863 4483);
FORCEPROP 2 LAST CDS_LIB mstr_standard
J 2
(-5925 4475);
DISPLAY 0.723404 (-5925 4475);
PAINT MONO (-5925 4475);
DISPLAY INVISIBLE (-5925 4475);
FORCEPROP 1 LAST BODY_TYPE PLUMBING
J 2
(-5925 4525);
DISPLAY 0.872340 (-5925 4525);
PAINT GREEN (-5925 4525);
DISPLAY INVISIBLE (-5925 4525);
FORCEPROP 1 LAST HDL_TAP TRUE
J 2
(-6250 4350);
DISPLAY 0.872340 (-6250 4350);
DISPLAY INVISIBLE (-6250 4350);
FORCEPROP 1 LAST PATH I284
J 2
(-5923 4475);
DISPLAY 0.872340 (-5923 4475);
PAINT GREEN (-5923 4475);
DISPLAY INVISIBLE (-5923 4475);
FORCEADD TAP..1
R 2
(-5925 4375);
FORCEPROP 3 LASTPIN (-5875 4375) SIG_NAME M_A_CPU1_SB_DQS_DN<6>
J 0
(-5865 4385);
DISPLAY 0.659574 (-5865 4385);
PAINT MONO (-5865 4385);
DISPLAY INVISIBLE (-5865 4385);
FORCEPROP 1 LASTPIN (-5875 4375) BN 6
J 2
(-5863 4383);
DISPLAY 0.489362 (-5863 4383);
PAINT GREEN (-5863 4383);
FORCEPROP 2 LAST CDS_LIB mstr_standard
J 2
(-5925 4375);
DISPLAY 0.723404 (-5925 4375);
PAINT MONO (-5925 4375);
DISPLAY INVISIBLE (-5925 4375);
FORCEPROP 1 LAST BODY_TYPE PLUMBING
J 2
(-5925 4425);
DISPLAY 0.872340 (-5925 4425);
PAINT GREEN (-5925 4425);
DISPLAY INVISIBLE (-5925 4425);
FORCEPROP 1 LAST HDL_TAP TRUE
J 2
(-6250 4250);
DISPLAY 0.872340 (-6250 4250);
DISPLAY INVISIBLE (-6250 4250);
FORCEPROP 1 LAST PATH I285
J 2
(-5923 4375);
DISPLAY 0.872340 (-5923 4375);
PAINT GREEN (-5923 4375);
DISPLAY INVISIBLE (-5923 4375);
FORCEADD TAP..1
R 2
(-5725 4325);
FORCEPROP 3 LASTPIN (-5675 4325) SIG_NAME M_A_CPU1_SB_DQS_DP<7>
J 0
(-5665 4335);
DISPLAY 0.659574 (-5665 4335);
PAINT MONO (-5665 4335);
DISPLAY INVISIBLE (-5665 4335);
FORCEPROP 1 LASTPIN (-5675 4325) BN 7
J 2
(-5663 4333);
DISPLAY 0.489362 (-5663 4333);
PAINT GREEN (-5663 4333);
FORCEPROP 2 LAST CDS_LIB mstr_standard
J 2
(-5725 4325);
DISPLAY 0.723404 (-5725 4325);
PAINT MONO (-5725 4325);
DISPLAY INVISIBLE (-5725 4325);
FORCEPROP 1 LAST BODY_TYPE PLUMBING
J 2
(-5725 4375);
DISPLAY 0.872340 (-5725 4375);
PAINT GREEN (-5725 4375);
DISPLAY INVISIBLE (-5725 4375);
FORCEPROP 1 LAST HDL_TAP TRUE
J 2
(-6050 4200);
DISPLAY 0.872340 (-6050 4200);
DISPLAY INVISIBLE (-6050 4200);
FORCEPROP 1 LAST PATH I286
J 2
(-5723 4325);
DISPLAY 0.872340 (-5723 4325);
PAINT GREEN (-5723 4325);
DISPLAY INVISIBLE (-5723 4325);
FORCEADD TAP..1
R 2
(-5725 4225);
FORCEPROP 3 LASTPIN (-5675 4225) SIG_NAME M_A_CPU1_SB_DQS_DP<8>
J 0
(-5665 4235);
DISPLAY 0.659574 (-5665 4235);
PAINT MONO (-5665 4235);
DISPLAY INVISIBLE (-5665 4235);
FORCEPROP 1 LASTPIN (-5675 4225) BN 8
J 2
(-5663 4233);
DISPLAY 0.489362 (-5663 4233);
PAINT GREEN (-5663 4233);
FORCEPROP 2 LAST CDS_LIB mstr_standard
J 2
(-5725 4225);
DISPLAY 0.723404 (-5725 4225);
PAINT MONO (-5725 4225);
DISPLAY INVISIBLE (-5725 4225);
FORCEPROP 1 LAST BODY_TYPE PLUMBING
J 2
(-5725 4275);
DISPLAY 0.872340 (-5725 4275);
PAINT GREEN (-5725 4275);
DISPLAY INVISIBLE (-5725 4275);
FORCEPROP 1 LAST HDL_TAP TRUE
J 2
(-6050 4100);
DISPLAY 0.872340 (-6050 4100);
DISPLAY INVISIBLE (-6050 4100);
FORCEPROP 1 LAST PATH I287
J 2
(-5723 4225);
DISPLAY 0.872340 (-5723 4225);
PAINT GREEN (-5723 4225);
DISPLAY INVISIBLE (-5723 4225);
FORCEADD TAP..1
R 2
(-5725 4125);
FORCEPROP 3 LASTPIN (-5675 4125) SIG_NAME M_A_CPU1_SB_DQS_DP<9>
J 0
(-5665 4135);
DISPLAY 0.659574 (-5665 4135);
PAINT MONO (-5665 4135);
DISPLAY INVISIBLE (-5665 4135);
FORCEPROP 1 LASTPIN (-5675 4125) BN 9
J 2
(-5663 4133);
DISPLAY 0.489362 (-5663 4133);
PAINT GREEN (-5663 4133);
FORCEPROP 2 LAST CDS_LIB mstr_standard
J 2
(-5725 4125);
DISPLAY 0.723404 (-5725 4125);
PAINT MONO (-5725 4125);
DISPLAY INVISIBLE (-5725 4125);
FORCEPROP 1 LAST BODY_TYPE PLUMBING
J 2
(-5725 4175);
DISPLAY 0.872340 (-5725 4175);
PAINT GREEN (-5725 4175);
DISPLAY INVISIBLE (-5725 4175);
FORCEPROP 1 LAST HDL_TAP TRUE
J 2
(-6050 4000);
DISPLAY 0.872340 (-6050 4000);
DISPLAY INVISIBLE (-6050 4000);
FORCEPROP 1 LAST PATH I288
J 2
(-5723 4125);
DISPLAY 0.872340 (-5723 4125);
PAINT GREEN (-5723 4125);
DISPLAY INVISIBLE (-5723 4125);
FORCEADD TAP..1
R 2
(-5925 4275);
FORCEPROP 3 LASTPIN (-5875 4275) SIG_NAME M_A_CPU1_SB_DQS_DN<7>
J 0
(-5865 4285);
DISPLAY 0.659574 (-5865 4285);
PAINT MONO (-5865 4285);
DISPLAY INVISIBLE (-5865 4285);
FORCEPROP 1 LASTPIN (-5875 4275) BN 7
J 2
(-5863 4283);
DISPLAY 0.489362 (-5863 4283);
PAINT GREEN (-5863 4283);
FORCEPROP 2 LAST CDS_LIB mstr_standard
J 2
(-5925 4275);
DISPLAY 0.723404 (-5925 4275);
PAINT MONO (-5925 4275);
DISPLAY INVISIBLE (-5925 4275);
FORCEPROP 1 LAST BODY_TYPE PLUMBING
J 2
(-5925 4325);
DISPLAY 0.872340 (-5925 4325);
PAINT GREEN (-5925 4325);
DISPLAY INVISIBLE (-5925 4325);
FORCEPROP 1 LAST HDL_TAP TRUE
J 2
(-6250 4150);
DISPLAY 0.872340 (-6250 4150);
DISPLAY INVISIBLE (-6250 4150);
FORCEPROP 1 LAST PATH I289
J 2
(-5923 4275);
DISPLAY 0.872340 (-5923 4275);
PAINT GREEN (-5923 4275);
DISPLAY INVISIBLE (-5923 4275);
FORCEADD TAP..1
R 2
(-5925 4175);
FORCEPROP 3 LASTPIN (-5875 4175) SIG_NAME M_A_CPU1_SB_DQS_DN<8>
J 0
(-5865 4185);
DISPLAY 0.659574 (-5865 4185);
PAINT MONO (-5865 4185);
DISPLAY INVISIBLE (-5865 4185);
FORCEPROP 1 LASTPIN (-5875 4175) BN 8
J 2
(-5863 4183);
DISPLAY 0.489362 (-5863 4183);
PAINT GREEN (-5863 4183);
FORCEPROP 2 LAST CDS_LIB mstr_standard
J 2
(-5925 4175);
DISPLAY 0.723404 (-5925 4175);
PAINT MONO (-5925 4175);
DISPLAY INVISIBLE (-5925 4175);
FORCEPROP 1 LAST BODY_TYPE PLUMBING
J 2
(-5925 4225);
DISPLAY 0.872340 (-5925 4225);
PAINT GREEN (-5925 4225);
DISPLAY INVISIBLE (-5925 4225);
FORCEPROP 1 LAST HDL_TAP TRUE
J 2
(-6250 4050);
DISPLAY 0.872340 (-6250 4050);
DISPLAY INVISIBLE (-6250 4050);
FORCEPROP 1 LAST PATH I290
J 2
(-5923 4175);
DISPLAY 0.872340 (-5923 4175);
PAINT GREEN (-5923 4175);
DISPLAY INVISIBLE (-5923 4175);
FORCEADD OFFPAGE..3
R 2
(-6625 6050);
FORCEPROP 2 LAST $XR0 98 
J 0
(-6874 6050);
DISPLAY 0.638298 (-6874 6050);
PAINT MONO (-6874 6050);
FORCEPROP 2 LAST CDS_LIB standard
J 0
(-6625 6050);
DISPLAY INVISIBLE (-6625 6050);
FORCEPROP 1 LAST OFFPAGE TRUE
J 2
(-6950 5925);
DISPLAY 0.872340 (-6950 5925);
PAINT GREEN (-6950 5925);
DISPLAY INVISIBLE (-6950 5925);
FORCEPROP 1 LAST COMMENT_BODY TRUE
J 2
(-6575 5950);
DISPLAY 0.872340 (-6575 5950);
PAINT GREEN (-6575 5950);
DISPLAY INVISIBLE (-6575 5950);
FORCEPROP 2 LAST PATH I291
J 0
(-6900 6100);
DISPLAY 1.021277 (-6900 6100);
DISPLAY INVISIBLE (-6900 6100);
FORCEADD OFFPAGE..3
R 2
(-6625 6100);
FORCEPROP 2 LAST $XR0 98 
J 0
(-6874 6100);
DISPLAY 0.638298 (-6874 6100);
PAINT MONO (-6874 6100);
FORCEPROP 2 LAST CDS_LIB standard
J 0
(-6625 6100);
DISPLAY INVISIBLE (-6625 6100);
FORCEPROP 1 LAST OFFPAGE TRUE
J 2
(-6950 5975);
DISPLAY 0.872340 (-6950 5975);
PAINT GREEN (-6950 5975);
DISPLAY INVISIBLE (-6950 5975);
FORCEPROP 1 LAST COMMENT_BODY TRUE
J 2
(-6575 6000);
DISPLAY 0.872340 (-6575 6000);
PAINT GREEN (-6575 6000);
DISPLAY INVISIBLE (-6575 6000);
FORCEPROP 2 LAST PATH I292
J 0
(-6900 6150);
DISPLAY 1.021277 (-6900 6150);
DISPLAY INVISIBLE (-6900 6150);
FORCEADD OFFPAGE..3
R 2
(-6625 5050);
FORCEPROP 2 LAST $XR0 98 
J 0
(-6874 5050);
DISPLAY 0.638298 (-6874 5050);
PAINT MONO (-6874 5050);
FORCEPROP 2 LAST CDS_LIB standard
J 0
(-6625 5050);
DISPLAY INVISIBLE (-6625 5050);
FORCEPROP 1 LAST OFFPAGE TRUE
J 2
(-6950 4925);
DISPLAY 0.872340 (-6950 4925);
PAINT GREEN (-6950 4925);
DISPLAY INVISIBLE (-6950 4925);
FORCEPROP 1 LAST COMMENT_BODY TRUE
J 2
(-6575 4950);
DISPLAY 0.872340 (-6575 4950);
PAINT GREEN (-6575 4950);
DISPLAY INVISIBLE (-6575 4950);
FORCEPROP 2 LAST PATH I293
J 0
(-6900 5100);
DISPLAY 1.021277 (-6900 5100);
DISPLAY INVISIBLE (-6900 5100);
FORCEADD OFFPAGE..3
R 2
(-6625 5000);
FORCEPROP 2 LAST $XR0 98 
J 0
(-6874 5000);
DISPLAY 0.638298 (-6874 5000);
PAINT MONO (-6874 5000);
FORCEPROP 2 LAST CDS_LIB standard
J 0
(-6625 5000);
DISPLAY INVISIBLE (-6625 5000);
FORCEPROP 1 LAST OFFPAGE TRUE
J 2
(-6950 4875);
DISPLAY 0.872340 (-6950 4875);
PAINT GREEN (-6950 4875);
DISPLAY INVISIBLE (-6950 4875);
FORCEPROP 1 LAST COMMENT_BODY TRUE
J 2
(-6575 4900);
DISPLAY 0.872340 (-6575 4900);
PAINT GREEN (-6575 4900);
DISPLAY INVISIBLE (-6575 4900);
FORCEPROP 2 LAST PATH I294
J 0
(-6900 5050);
DISPLAY 1.021277 (-6900 5050);
DISPLAY INVISIBLE (-6900 5050);
FORCEADD TAP..1
R 2
(-5925 4075);
FORCEPROP 3 LASTPIN (-5875 4075) SIG_NAME M_A_CPU1_SB_DQS_DN<9>
J 0
(-5865 4085);
DISPLAY 0.659574 (-5865 4085);
PAINT MONO (-5865 4085);
DISPLAY INVISIBLE (-5865 4085);
FORCEPROP 1 LASTPIN (-5875 4075) BN 9
J 2
(-5863 4083);
DISPLAY 0.489362 (-5863 4083);
PAINT GREEN (-5863 4083);
FORCEPROP 2 LAST CDS_LIB mstr_standard
J 2
(-5925 4075);
DISPLAY 0.723404 (-5925 4075);
PAINT MONO (-5925 4075);
DISPLAY INVISIBLE (-5925 4075);
FORCEPROP 1 LAST BODY_TYPE PLUMBING
J 2
(-5925 4125);
DISPLAY 0.872340 (-5925 4125);
PAINT GREEN (-5925 4125);
DISPLAY INVISIBLE (-5925 4125);
FORCEPROP 1 LAST HDL_TAP TRUE
J 2
(-6250 3950);
DISPLAY 0.872340 (-6250 3950);
DISPLAY INVISIBLE (-6250 3950);
FORCEPROP 1 LAST PATH I295
J 2
(-5923 4075);
DISPLAY 0.872340 (-5923 4075);
PAINT GREEN (-5923 4075);
DISPLAY INVISIBLE (-5923 4075);
FORCEADD TAP..1
R 2
(-5925 3925);
FORCEPROP 3 LASTPIN (-5875 3925) SIG_NAME M_A_CPU1_SA_CA<0>
J 0
(-5865 3935);
DISPLAY 0.659574 (-5865 3935);
PAINT MONO (-5865 3935);
DISPLAY INVISIBLE (-5865 3935);
FORCEPROP 1 LASTPIN (-5875 3925) BN 0
J 2
(-5863 3933);
DISPLAY 0.489362 (-5863 3933);
PAINT GREEN (-5863 3933);
FORCEPROP 2 LAST CDS_LIB mstr_standard
J 0
(-5925 3925);
DISPLAY 0.723404 (-5925 3925);
PAINT MONO (-5925 3925);
DISPLAY INVISIBLE (-5925 3925);
FORCEPROP 1 LAST BODY_TYPE PLUMBING
J 2
(-5925 3975);
DISPLAY 0.872340 (-5925 3975);
PAINT GREEN (-5925 3975);
DISPLAY INVISIBLE (-5925 3975);
FORCEPROP 1 LAST HDL_TAP TRUE
J 2
(-6250 3800);
DISPLAY 0.872340 (-6250 3800);
DISPLAY INVISIBLE (-6250 3800);
FORCEPROP 1 LAST PATH I296
J 2
(-5923 3925);
DISPLAY 0.872340 (-5923 3925);
PAINT GREEN (-5923 3925);
DISPLAY INVISIBLE (-5923 3925);
FORCEADD TAP..1
R 2
(-5925 3875);
FORCEPROP 3 LASTPIN (-5875 3875) SIG_NAME M_A_CPU1_SA_CA<1>
J 0
(-5865 3885);
DISPLAY 0.659574 (-5865 3885);
PAINT MONO (-5865 3885);
DISPLAY INVISIBLE (-5865 3885);
FORCEPROP 1 LASTPIN (-5875 3875) BN 1
J 2
(-5863 3883);
DISPLAY 0.489362 (-5863 3883);
PAINT GREEN (-5863 3883);
FORCEPROP 2 LAST CDS_LIB mstr_standard
J 0
(-5925 3875);
DISPLAY 0.723404 (-5925 3875);
PAINT MONO (-5925 3875);
DISPLAY INVISIBLE (-5925 3875);
FORCEPROP 1 LAST BODY_TYPE PLUMBING
J 2
(-5925 3925);
DISPLAY 0.872340 (-5925 3925);
PAINT GREEN (-5925 3925);
DISPLAY INVISIBLE (-5925 3925);
FORCEPROP 1 LAST HDL_TAP TRUE
J 2
(-6250 3750);
DISPLAY 0.872340 (-6250 3750);
DISPLAY INVISIBLE (-6250 3750);
FORCEPROP 1 LAST PATH I297
J 2
(-5923 3875);
DISPLAY 0.872340 (-5923 3875);
PAINT GREEN (-5923 3875);
DISPLAY INVISIBLE (-5923 3875);
FORCEADD TAP..1
R 2
(-5925 3825);
FORCEPROP 3 LASTPIN (-5875 3825) SIG_NAME M_A_CPU1_SA_CA<2>
J 0
(-5865 3835);
DISPLAY 0.659574 (-5865 3835);
PAINT MONO (-5865 3835);
DISPLAY INVISIBLE (-5865 3835);
FORCEPROP 1 LASTPIN (-5875 3825) BN 2
J 2
(-5863 3833);
DISPLAY 0.489362 (-5863 3833);
PAINT GREEN (-5863 3833);
FORCEPROP 2 LAST CDS_LIB mstr_standard
J 0
(-5925 3825);
DISPLAY 0.723404 (-5925 3825);
PAINT MONO (-5925 3825);
DISPLAY INVISIBLE (-5925 3825);
FORCEPROP 1 LAST BODY_TYPE PLUMBING
J 2
(-5925 3875);
DISPLAY 0.872340 (-5925 3875);
PAINT GREEN (-5925 3875);
DISPLAY INVISIBLE (-5925 3875);
FORCEPROP 1 LAST HDL_TAP TRUE
J 2
(-6250 3700);
DISPLAY 0.872340 (-6250 3700);
DISPLAY INVISIBLE (-6250 3700);
FORCEPROP 1 LAST PATH I298
J 2
(-5923 3825);
DISPLAY 0.872340 (-5923 3825);
PAINT GREEN (-5923 3825);
DISPLAY INVISIBLE (-5923 3825);
FORCEADD TAP..1
R 2
(-5925 3775);
FORCEPROP 3 LASTPIN (-5875 3775) SIG_NAME M_A_CPU1_SA_CA<3>
J 0
(-5865 3785);
DISPLAY 0.659574 (-5865 3785);
PAINT MONO (-5865 3785);
DISPLAY INVISIBLE (-5865 3785);
FORCEPROP 1 LASTPIN (-5875 3775) BN 3
J 2
(-5863 3783);
DISPLAY 0.489362 (-5863 3783);
PAINT GREEN (-5863 3783);
FORCEPROP 2 LAST CDS_LIB mstr_standard
J 0
(-5925 3775);
DISPLAY 0.723404 (-5925 3775);
PAINT MONO (-5925 3775);
DISPLAY INVISIBLE (-5925 3775);
FORCEPROP 1 LAST BODY_TYPE PLUMBING
J 2
(-5925 3825);
DISPLAY 0.872340 (-5925 3825);
PAINT GREEN (-5925 3825);
DISPLAY INVISIBLE (-5925 3825);
FORCEPROP 1 LAST HDL_TAP TRUE
J 2
(-6250 3650);
DISPLAY 0.872340 (-6250 3650);
DISPLAY INVISIBLE (-6250 3650);
FORCEPROP 1 LAST PATH I299
J 2
(-5923 3775);
DISPLAY 0.872340 (-5923 3775);
PAINT GREEN (-5923 3775);
DISPLAY INVISIBLE (-5923 3775);
FORCEADD TAP..1
R 2
(-5925 3725);
FORCEPROP 3 LASTPIN (-5875 3725) SIG_NAME M_A_CPU1_SA_CA<4>
J 0
(-5865 3735);
DISPLAY 0.659574 (-5865 3735);
PAINT MONO (-5865 3735);
DISPLAY INVISIBLE (-5865 3735);
FORCEPROP 1 LASTPIN (-5875 3725) BN 4
J 2
(-5863 3733);
DISPLAY 0.489362 (-5863 3733);
PAINT GREEN (-5863 3733);
FORCEPROP 2 LAST CDS_LIB mstr_standard
J 0
(-5925 3725);
DISPLAY 0.723404 (-5925 3725);
PAINT MONO (-5925 3725);
DISPLAY INVISIBLE (-5925 3725);
FORCEPROP 1 LAST BODY_TYPE PLUMBING
J 2
(-5925 3775);
DISPLAY 0.872340 (-5925 3775);
PAINT GREEN (-5925 3775);
DISPLAY INVISIBLE (-5925 3775);
FORCEPROP 1 LAST HDL_TAP TRUE
J 2
(-6250 3600);
DISPLAY 0.872340 (-6250 3600);
DISPLAY INVISIBLE (-6250 3600);
FORCEPROP 1 LAST PATH I300
J 2
(-5923 3725);
DISPLAY 0.872340 (-5923 3725);
PAINT GREEN (-5923 3725);
DISPLAY INVISIBLE (-5923 3725);
FORCEADD TAP..1
R 2
(-5925 3675);
FORCEPROP 3 LASTPIN (-5875 3675) SIG_NAME M_A_CPU1_SA_CA<5>
J 0
(-5865 3685);
DISPLAY 0.659574 (-5865 3685);
PAINT MONO (-5865 3685);
DISPLAY INVISIBLE (-5865 3685);
FORCEPROP 1 LASTPIN (-5875 3675) BN 5
J 2
(-5863 3683);
DISPLAY 0.489362 (-5863 3683);
PAINT GREEN (-5863 3683);
FORCEPROP 2 LAST CDS_LIB mstr_standard
J 0
(-5925 3675);
DISPLAY 0.723404 (-5925 3675);
PAINT MONO (-5925 3675);
DISPLAY INVISIBLE (-5925 3675);
FORCEPROP 1 LAST BODY_TYPE PLUMBING
J 2
(-5925 3725);
DISPLAY 0.872340 (-5925 3725);
PAINT GREEN (-5925 3725);
DISPLAY INVISIBLE (-5925 3725);
FORCEPROP 1 LAST HDL_TAP TRUE
J 2
(-6250 3550);
DISPLAY 0.872340 (-6250 3550);
DISPLAY INVISIBLE (-6250 3550);
FORCEPROP 1 LAST PATH I301
J 2
(-5923 3675);
DISPLAY 0.872340 (-5923 3675);
PAINT GREEN (-5923 3675);
DISPLAY INVISIBLE (-5923 3675);
FORCEADD TAP..1
R 2
(-5925 3625);
FORCEPROP 3 LASTPIN (-5875 3625) SIG_NAME M_A_CPU1_SA_CA<6>
J 0
(-5865 3635);
DISPLAY 0.659574 (-5865 3635);
PAINT MONO (-5865 3635);
DISPLAY INVISIBLE (-5865 3635);
FORCEPROP 1 LASTPIN (-5875 3625) BN 6
J 2
(-5863 3633);
DISPLAY 0.489362 (-5863 3633);
PAINT GREEN (-5863 3633);
FORCEPROP 2 LAST CDS_LIB mstr_standard
J 0
(-5925 3625);
DISPLAY 0.723404 (-5925 3625);
PAINT MONO (-5925 3625);
DISPLAY INVISIBLE (-5925 3625);
FORCEPROP 1 LAST BODY_TYPE PLUMBING
J 2
(-5925 3675);
DISPLAY 0.872340 (-5925 3675);
PAINT GREEN (-5925 3675);
DISPLAY INVISIBLE (-5925 3675);
FORCEPROP 1 LAST HDL_TAP TRUE
J 2
(-6250 3500);
DISPLAY 0.872340 (-6250 3500);
DISPLAY INVISIBLE (-6250 3500);
FORCEPROP 1 LAST PATH I302
J 2
(-5923 3625);
DISPLAY 0.872340 (-5923 3625);
PAINT GREEN (-5923 3625);
DISPLAY INVISIBLE (-5923 3625);
FORCEADD TAP..1
R 2
(-5925 3475);
FORCEPROP 3 LASTPIN (-5875 3475) SIG_NAME M_A_CPU1_SB_CA<1>
J 0
(-5865 3485);
DISPLAY 0.659574 (-5865 3485);
PAINT MONO (-5865 3485);
DISPLAY INVISIBLE (-5865 3485);
FORCEPROP 1 LASTPIN (-5875 3475) BN 1
J 2
(-5863 3483);
DISPLAY 0.489362 (-5863 3483);
PAINT GREEN (-5863 3483);
FORCEPROP 2 LAST CDS_LIB mstr_standard
J 0
(-5925 3475);
DISPLAY 0.723404 (-5925 3475);
PAINT MONO (-5925 3475);
DISPLAY INVISIBLE (-5925 3475);
FORCEPROP 1 LAST BODY_TYPE PLUMBING
J 2
(-5925 3525);
DISPLAY 0.872340 (-5925 3525);
PAINT GREEN (-5925 3525);
DISPLAY INVISIBLE (-5925 3525);
FORCEPROP 1 LAST HDL_TAP TRUE
J 2
(-6250 3350);
DISPLAY 0.872340 (-6250 3350);
DISPLAY INVISIBLE (-6250 3350);
FORCEPROP 1 LAST PATH I303
J 2
(-5923 3475);
DISPLAY 0.872340 (-5923 3475);
PAINT GREEN (-5923 3475);
DISPLAY INVISIBLE (-5923 3475);
FORCEADD TAP..1
R 2
(-5925 3525);
FORCEPROP 3 LASTPIN (-5875 3525) SIG_NAME M_A_CPU1_SB_CA<0>
J 0
(-5865 3535);
DISPLAY 0.659574 (-5865 3535);
PAINT MONO (-5865 3535);
DISPLAY INVISIBLE (-5865 3535);
FORCEPROP 1 LASTPIN (-5875 3525) BN 0
J 2
(-5863 3533);
DISPLAY 0.489362 (-5863 3533);
PAINT GREEN (-5863 3533);
FORCEPROP 2 LAST CDS_LIB mstr_standard
J 0
(-5925 3525);
DISPLAY 0.723404 (-5925 3525);
PAINT MONO (-5925 3525);
DISPLAY INVISIBLE (-5925 3525);
FORCEPROP 1 LAST BODY_TYPE PLUMBING
J 2
(-5925 3575);
DISPLAY 0.872340 (-5925 3575);
PAINT GREEN (-5925 3575);
DISPLAY INVISIBLE (-5925 3575);
FORCEPROP 1 LAST HDL_TAP TRUE
J 2
(-6250 3400);
DISPLAY 0.872340 (-6250 3400);
DISPLAY INVISIBLE (-6250 3400);
FORCEPROP 1 LAST PATH I304
J 2
(-5923 3525);
DISPLAY 0.872340 (-5923 3525);
PAINT GREEN (-5923 3525);
DISPLAY INVISIBLE (-5923 3525);
FORCEADD TAP..1
R 2
(-5925 3425);
FORCEPROP 3 LASTPIN (-5875 3425) SIG_NAME M_A_CPU1_SB_CA<2>
J 0
(-5865 3435);
DISPLAY 0.659574 (-5865 3435);
PAINT MONO (-5865 3435);
DISPLAY INVISIBLE (-5865 3435);
FORCEPROP 1 LASTPIN (-5875 3425) BN 2
J 2
(-5863 3433);
DISPLAY 0.489362 (-5863 3433);
PAINT GREEN (-5863 3433);
FORCEPROP 2 LAST CDS_LIB mstr_standard
J 0
(-5925 3425);
DISPLAY 0.723404 (-5925 3425);
PAINT MONO (-5925 3425);
DISPLAY INVISIBLE (-5925 3425);
FORCEPROP 1 LAST BODY_TYPE PLUMBING
J 2
(-5925 3475);
DISPLAY 0.872340 (-5925 3475);
PAINT GREEN (-5925 3475);
DISPLAY INVISIBLE (-5925 3475);
FORCEPROP 1 LAST HDL_TAP TRUE
J 2
(-6250 3300);
DISPLAY 0.872340 (-6250 3300);
DISPLAY INVISIBLE (-6250 3300);
FORCEPROP 1 LAST PATH I305
J 2
(-5923 3425);
DISPLAY 0.872340 (-5923 3425);
PAINT GREEN (-5923 3425);
DISPLAY INVISIBLE (-5923 3425);
FORCEADD TAP..1
R 2
(-5925 3375);
FORCEPROP 3 LASTPIN (-5875 3375) SIG_NAME M_A_CPU1_SB_CA<3>
J 0
(-5865 3385);
DISPLAY 0.659574 (-5865 3385);
PAINT MONO (-5865 3385);
DISPLAY INVISIBLE (-5865 3385);
FORCEPROP 1 LASTPIN (-5875 3375) BN 3
J 2
(-5863 3383);
DISPLAY 0.489362 (-5863 3383);
PAINT GREEN (-5863 3383);
FORCEPROP 2 LAST CDS_LIB mstr_standard
J 0
(-5925 3375);
DISPLAY 0.723404 (-5925 3375);
PAINT MONO (-5925 3375);
DISPLAY INVISIBLE (-5925 3375);
FORCEPROP 1 LAST BODY_TYPE PLUMBING
J 2
(-5925 3425);
DISPLAY 0.872340 (-5925 3425);
PAINT GREEN (-5925 3425);
DISPLAY INVISIBLE (-5925 3425);
FORCEPROP 1 LAST HDL_TAP TRUE
J 2
(-6250 3250);
DISPLAY 0.872340 (-6250 3250);
DISPLAY INVISIBLE (-6250 3250);
FORCEPROP 1 LAST PATH I306
J 2
(-5923 3375);
DISPLAY 0.872340 (-5923 3375);
PAINT GREEN (-5923 3375);
DISPLAY INVISIBLE (-5923 3375);
FORCEADD TAP..1
R 2
(-5925 3325);
FORCEPROP 3 LASTPIN (-5875 3325) SIG_NAME M_A_CPU1_SB_CA<4>
J 0
(-5865 3335);
DISPLAY 0.659574 (-5865 3335);
PAINT MONO (-5865 3335);
DISPLAY INVISIBLE (-5865 3335);
FORCEPROP 1 LASTPIN (-5875 3325) BN 4
J 2
(-5863 3333);
DISPLAY 0.489362 (-5863 3333);
PAINT GREEN (-5863 3333);
FORCEPROP 2 LAST CDS_LIB mstr_standard
J 0
(-5925 3325);
DISPLAY 0.723404 (-5925 3325);
PAINT MONO (-5925 3325);
DISPLAY INVISIBLE (-5925 3325);
FORCEPROP 1 LAST BODY_TYPE PLUMBING
J 2
(-5925 3375);
DISPLAY 0.872340 (-5925 3375);
PAINT GREEN (-5925 3375);
DISPLAY INVISIBLE (-5925 3375);
FORCEPROP 1 LAST HDL_TAP TRUE
J 2
(-6250 3200);
DISPLAY 0.872340 (-6250 3200);
DISPLAY INVISIBLE (-6250 3200);
FORCEPROP 1 LAST PATH I307
J 2
(-5923 3325);
DISPLAY 0.872340 (-5923 3325);
PAINT GREEN (-5923 3325);
DISPLAY INVISIBLE (-5923 3325);
FORCEADD TAP..1
R 2
(-5925 3225);
FORCEPROP 3 LASTPIN (-5875 3225) SIG_NAME M_A_CPU1_SB_CA<6>
J 0
(-5865 3235);
DISPLAY 0.659574 (-5865 3235);
PAINT MONO (-5865 3235);
DISPLAY INVISIBLE (-5865 3235);
FORCEPROP 1 LASTPIN (-5875 3225) BN 6
J 2
(-5863 3233);
DISPLAY 0.489362 (-5863 3233);
PAINT GREEN (-5863 3233);
FORCEPROP 2 LAST CDS_LIB mstr_standard
J 0
(-5925 3225);
DISPLAY 0.723404 (-5925 3225);
PAINT MONO (-5925 3225);
DISPLAY INVISIBLE (-5925 3225);
FORCEPROP 1 LAST BODY_TYPE PLUMBING
J 2
(-5925 3275);
DISPLAY 0.872340 (-5925 3275);
PAINT GREEN (-5925 3275);
DISPLAY INVISIBLE (-5925 3275);
FORCEPROP 1 LAST HDL_TAP TRUE
J 2
(-6250 3100);
DISPLAY 0.872340 (-6250 3100);
DISPLAY INVISIBLE (-6250 3100);
FORCEPROP 1 LAST PATH I308
J 2
(-5923 3225);
DISPLAY 0.872340 (-5923 3225);
PAINT GREEN (-5923 3225);
DISPLAY INVISIBLE (-5923 3225);
FORCEADD TAP..1
R 2
(-5925 3275);
FORCEPROP 3 LASTPIN (-5875 3275) SIG_NAME M_A_CPU1_SB_CA<5>
J 0
(-5865 3285);
DISPLAY 0.659574 (-5865 3285);
PAINT MONO (-5865 3285);
DISPLAY INVISIBLE (-5865 3285);
FORCEPROP 1 LASTPIN (-5875 3275) BN 5
J 2
(-5863 3283);
DISPLAY 0.489362 (-5863 3283);
PAINT GREEN (-5863 3283);
FORCEPROP 2 LAST CDS_LIB mstr_standard
J 0
(-5925 3275);
DISPLAY 0.723404 (-5925 3275);
PAINT MONO (-5925 3275);
DISPLAY INVISIBLE (-5925 3275);
FORCEPROP 1 LAST BODY_TYPE PLUMBING
J 2
(-5925 3325);
DISPLAY 0.872340 (-5925 3325);
PAINT GREEN (-5925 3325);
DISPLAY INVISIBLE (-5925 3325);
FORCEPROP 1 LAST HDL_TAP TRUE
J 2
(-6250 3150);
DISPLAY 0.872340 (-6250 3150);
DISPLAY INVISIBLE (-6250 3150);
FORCEPROP 1 LAST PATH I309
J 2
(-5923 3275);
DISPLAY 0.872340 (-5923 3275);
PAINT GREEN (-5923 3275);
DISPLAY INVISIBLE (-5923 3275);
FORCEADD OFFPAGE..2
R 2
(-6525 3950);
FORCEPROP 2 LAST $XR0 98 
J 0
(-6749 3950);
DISPLAY 0.638298 (-6749 3950);
PAINT MONO (-6749 3950);
FORCEPROP 2 LAST CDS_LIB standard
J 0
(-6525 3950);
DISPLAY INVISIBLE (-6525 3950);
FORCEPROP 1 LAST OFFPAGE TRUE
J 2
(-6850 3825);
DISPLAY 0.872340 (-6850 3825);
PAINT GREEN (-6850 3825);
DISPLAY INVISIBLE (-6850 3825);
FORCEPROP 1 LAST COMMENT_BODY TRUE
J 2
(-6480 3855);
DISPLAY 0.872340 (-6480 3855);
PAINT GREEN (-6480 3855);
DISPLAY INVISIBLE (-6480 3855);
FORCEPROP 2 LAST PATH I310
J 0
(-6775 4000);
DISPLAY 1.021277 (-6775 4000);
DISPLAY INVISIBLE (-6775 4000);
FORCEADD OFFPAGE..2
R 2
(-6525 3550);
FORCEPROP 2 LAST $XR0 98 
J 0
(-6749 3550);
DISPLAY 0.638298 (-6749 3550);
PAINT MONO (-6749 3550);
FORCEPROP 2 LAST CDS_LIB standard
J 0
(-6525 3550);
DISPLAY INVISIBLE (-6525 3550);
FORCEPROP 1 LAST OFFPAGE TRUE
J 2
(-6850 3425);
DISPLAY 0.872340 (-6850 3425);
PAINT GREEN (-6850 3425);
DISPLAY INVISIBLE (-6850 3425);
FORCEPROP 1 LAST COMMENT_BODY TRUE
J 2
(-6480 3455);
DISPLAY 0.872340 (-6480 3455);
PAINT GREEN (-6480 3455);
DISPLAY INVISIBLE (-6480 3455);
FORCEPROP 2 LAST PATH I311
J 0
(-6775 3600);
DISPLAY 1.021277 (-6775 3600);
DISPLAY INVISIBLE (-6775 3600);
FORCEADD OFFPAGE..2
R 2
(-6525 3075);
FORCEPROP 2 LAST $XR0 98 
J 0
(-6749 3075);
DISPLAY 0.638298 (-6749 3075);
PAINT MONO (-6749 3075);
FORCEPROP 2 LAST CDS_LIB standard
J 0
(-6525 3075);
DISPLAY INVISIBLE (-6525 3075);
FORCEPROP 1 LAST OFFPAGE TRUE
J 2
(-6850 2950);
DISPLAY 0.872340 (-6850 2950);
PAINT GREEN (-6850 2950);
DISPLAY INVISIBLE (-6850 2950);
FORCEPROP 1 LAST COMMENT_BODY TRUE
J 2
(-6480 2980);
DISPLAY 0.872340 (-6480 2980);
PAINT GREEN (-6480 2980);
DISPLAY INVISIBLE (-6480 2980);
FORCEPROP 2 LAST PATH I312
J 0
(-6775 3125);
DISPLAY 1.021277 (-6775 3125);
DISPLAY INVISIBLE (-6775 3125);
FORCEADD OFFPAGE..2
R 2
(-6525 3025);
FORCEPROP 2 LAST $XR0 98 
J 0
(-6749 3025);
DISPLAY 0.638298 (-6749 3025);
PAINT MONO (-6749 3025);
FORCEPROP 2 LAST CDS_LIB standard
J 0
(-6525 3025);
DISPLAY INVISIBLE (-6525 3025);
FORCEPROP 1 LAST OFFPAGE TRUE
J 2
(-6850 2900);
DISPLAY 0.872340 (-6850 2900);
PAINT GREEN (-6850 2900);
DISPLAY INVISIBLE (-6850 2900);
FORCEPROP 1 LAST COMMENT_BODY TRUE
J 2
(-6480 2930);
DISPLAY 0.872340 (-6480 2930);
PAINT GREEN (-6480 2930);
DISPLAY INVISIBLE (-6480 2930);
FORCEPROP 2 LAST PATH I313
J 0
(-6775 3075);
DISPLAY 1.021277 (-6775 3075);
DISPLAY INVISIBLE (-6775 3075);
FORCEADD OFFPAGE..2
R 2
(-6525 2925);
FORCEPROP 2 LAST $XR0 98 
J 0
(-6749 2925);
DISPLAY 0.638298 (-6749 2925);
PAINT MONO (-6749 2925);
FORCEPROP 2 LAST CDS_LIB standard
J 0
(-6525 2925);
DISPLAY INVISIBLE (-6525 2925);
FORCEPROP 1 LAST OFFPAGE TRUE
J 2
(-6850 2800);
DISPLAY 0.872340 (-6850 2800);
PAINT GREEN (-6850 2800);
DISPLAY INVISIBLE (-6850 2800);
FORCEPROP 1 LAST COMMENT_BODY TRUE
J 2
(-6480 2830);
DISPLAY 0.872340 (-6480 2830);
PAINT GREEN (-6480 2830);
DISPLAY INVISIBLE (-6480 2830);
FORCEPROP 2 LAST PATH I314
J 0
(-6775 2975);
DISPLAY 1.021277 (-6775 2975);
DISPLAY INVISIBLE (-6775 2975);
FORCEADD OFFPAGE..2
R 2
(-6525 2875);
FORCEPROP 2 LAST $XR0 98 
J 0
(-6749 2875);
DISPLAY 0.638298 (-6749 2875);
PAINT MONO (-6749 2875);
FORCEPROP 2 LAST CDS_LIB standard
J 0
(-6525 2875);
DISPLAY INVISIBLE (-6525 2875);
FORCEPROP 1 LAST OFFPAGE TRUE
J 2
(-6850 2750);
DISPLAY 0.872340 (-6850 2750);
PAINT GREEN (-6850 2750);
DISPLAY INVISIBLE (-6850 2750);
FORCEPROP 1 LAST COMMENT_BODY TRUE
J 2
(-6480 2780);
DISPLAY 0.872340 (-6480 2780);
PAINT GREEN (-6480 2780);
DISPLAY INVISIBLE (-6480 2780);
FORCEPROP 2 LAST PATH I315
J 0
(-6775 2925);
DISPLAY 1.021277 (-6775 2925);
DISPLAY INVISIBLE (-6775 2925);
FORCEADD OFFPAGE..1
(-6525 2775);
FORCEPROP 2 LAST $XR0 98 
J 0
(-6746 2775);
DISPLAY 0.638298 (-6746 2775);
PAINT MONO (-6746 2775);
FORCEPROP 2 LAST CDS_LIB standard
J 0
(-6525 2775);
DISPLAY INVISIBLE (-6525 2775);
FORCEPROP 1 LAST OFFPAGE TRUE
J 0
(-6200 2650);
DISPLAY 0.872340 (-6200 2650);
PAINT GREEN (-6200 2650);
DISPLAY INVISIBLE (-6200 2650);
FORCEPROP 1 LAST COMMENT_BODY TRUE
J 0
(-6400 2675);
DISPLAY 0.872340 (-6400 2675);
PAINT GREEN (-6400 2675);
DISPLAY INVISIBLE (-6400 2675);
FORCEPROP 2 LAST PATH I316
J 0
(-6775 2825);
DISPLAY 1.021277 (-6775 2825);
DISPLAY INVISIBLE (-6775 2825);
FORCEADD OFFPAGE..5
(-6525 2675);
FORCEPROP 2 LAST $XR0 98 
J 0
(-6749 2675);
DISPLAY 0.638298 (-6749 2675);
PAINT MONO (-6749 2675);
FORCEPROP 2 LAST CDS_LIB mstr_standard
J 0
(-6525 2675);
DISPLAY INVISIBLE (-6525 2675);
FORCEPROP 1 LAST OFFPAGE TRUE
J 0
(-6200 2550);
DISPLAY 0.872340 (-6200 2550);
PAINT GREEN (-6200 2550);
DISPLAY INVISIBLE (-6200 2550);
FORCEPROP 1 LAST COMMENT_BODY TRUE
J 0
(-6425 2600);
DISPLAY 0.872340 (-6425 2600);
PAINT GREEN (-6425 2600);
DISPLAY INVISIBLE (-6425 2600);
FORCEPROP 2 LAST PATH I317
J 0
(-6775 2725);
DISPLAY 1.021277 (-6775 2725);
DISPLAY INVISIBLE (-6775 2725);
FORCEADD OFFPAGE..2
R 2
(-6525 2575);
FORCEPROP 2 LAST $XR0 98 
J 0
(-6749 2575);
DISPLAY 0.638298 (-6749 2575);
PAINT MONO (-6749 2575);
FORCEPROP 2 LAST CDS_LIB standard
J 0
(-6525 2575);
DISPLAY INVISIBLE (-6525 2575);
FORCEPROP 1 LAST OFFPAGE TRUE
J 2
(-6850 2450);
DISPLAY 0.872340 (-6850 2450);
PAINT GREEN (-6850 2450);
DISPLAY INVISIBLE (-6850 2450);
FORCEPROP 1 LAST COMMENT_BODY TRUE
J 2
(-6480 2480);
DISPLAY 0.872340 (-6480 2480);
PAINT GREEN (-6480 2480);
DISPLAY INVISIBLE (-6480 2480);
FORCEPROP 2 LAST PATH I318
J 0
(-6775 2625);
DISPLAY 1.021277 (-6775 2625);
DISPLAY INVISIBLE (-6775 2625);
FORCEADD OFFPAGE..2
R 2
(-6525 2525);
FORCEPROP 2 LAST $XR0 98 
J 0
(-6749 2525);
DISPLAY 0.638298 (-6749 2525);
PAINT MONO (-6749 2525);
FORCEPROP 2 LAST CDS_LIB standard
J 0
(-6525 2525);
DISPLAY INVISIBLE (-6525 2525);
FORCEPROP 1 LAST OFFPAGE TRUE
J 2
(-6850 2400);
DISPLAY 0.872340 (-6850 2400);
PAINT GREEN (-6850 2400);
DISPLAY INVISIBLE (-6850 2400);
FORCEPROP 1 LAST COMMENT_BODY TRUE
J 2
(-6480 2430);
DISPLAY 0.872340 (-6480 2430);
PAINT GREEN (-6480 2430);
DISPLAY INVISIBLE (-6480 2430);
FORCEPROP 2 LAST PATH I319
J 0
(-6775 2575);
DISPLAY 1.021277 (-6775 2575);
DISPLAY INVISIBLE (-6775 2575);
FORCEADD OFFPAGE..1
(-6525 2425);
FORCEPROP 2 LAST $XR0 98 
J 0
(-6746 2425);
DISPLAY 0.638298 (-6746 2425);
PAINT MONO (-6746 2425);
FORCEPROP 2 LAST CDS_LIB standard
J 0
(-6525 2425);
DISPLAY INVISIBLE (-6525 2425);
FORCEPROP 1 LAST OFFPAGE TRUE
J 0
(-6200 2300);
DISPLAY 0.872340 (-6200 2300);
PAINT GREEN (-6200 2300);
DISPLAY INVISIBLE (-6200 2300);
FORCEPROP 1 LAST COMMENT_BODY TRUE
J 0
(-6400 2325);
DISPLAY 0.872340 (-6400 2325);
PAINT GREEN (-6400 2325);
DISPLAY INVISIBLE (-6400 2325);
FORCEPROP 2 LAST PATH I320
J 0
(-6775 2475);
DISPLAY 1.021277 (-6775 2475);
DISPLAY INVISIBLE (-6775 2475);
FORCEADD OFFPAGE..5
(-6525 2325);
FORCEPROP 2 LAST $XR0 98 
J 0
(-6749 2325);
DISPLAY 0.638298 (-6749 2325);
PAINT MONO (-6749 2325);
FORCEPROP 2 LAST CDS_LIB standard
J 0
(-6525 2325);
DISPLAY INVISIBLE (-6525 2325);
FORCEPROP 1 LAST OFFPAGE TRUE
J 0
(-6200 2200);
DISPLAY 0.872340 (-6200 2200);
PAINT GREEN (-6200 2200);
DISPLAY INVISIBLE (-6200 2200);
FORCEPROP 1 LAST COMMENT_BODY TRUE
J 0
(-6425 2250);
DISPLAY 0.872340 (-6425 2250);
PAINT GREEN (-6425 2250);
DISPLAY INVISIBLE (-6425 2250);
FORCEPROP 2 LAST PATH I321
J 0
(-6775 2375);
DISPLAY 1.021277 (-6775 2375);
DISPLAY INVISIBLE (-6775 2375);
FORCEADD Q_RES..1
(-6600 2225);
FORCEPROP 1 LAST LOCATION R500
J 0
(-6925 2225);
DISPLAY 0.489362 (-6925 2225);
PAINT SKYBLUE (-6925 2225);
FORCEPROP 0 LAST $SEC 1
J 0
(-6775 2275);
DISPLAY 0.680851 (-6775 2275);
PAINT MONO (-6775 2275);
DISPLAY INVISIBLE (-6775 2275);
FORCEPROP 0 LAST CDS_SEC 1
J 0
(-6775 2275);
DISPLAY 1.021277 (-6775 2275);
DISPLAY INVISIBLE (-6775 2275);
FORCEPROP 1 LASTPIN (-6700 2225) $PN 1
J 0
(-6688 2237);
DISPLAY 0.489362 (-6688 2237);
PAINT MONO (-6688 2237);
FORCEPROP 1 LASTPIN (-6500 2225) $PN 2
J 0
(-6538 2237);
DISPLAY 0.489362 (-6538 2237);
PAINT MONO (-6538 2237);
FORCEPROP 1 LAST PACK_TYPE 0402LF
J 0
(-6925 2200);
DISPLAY 0.489362 (-6925 2200);
PAINT SKYBLUE (-6925 2200);
FORCEPROP 1 LAST TOLERANCE 1%
J 0
(-6325 2225);
DISPLAY 0.489362 (-6325 2225);
PAINT SKYBLUE (-6325 2225);
FORCEPROP 1 LAST VALUE 15
J 2
(-6275 2225);
DISPLAY 0.489362 (-6275 2225);
PAINT SKYBLUE (-6275 2225);
FORCEPROP 1 LAST MATERIAL CHIP
J 0
(-6725 2350);
DISPLAY 0.638298 (-6725 2350);
PAINT SKYBLUE (-6725 2350);
DISPLAY INVISIBLE (-6725 2350);
FORCEPROP 1 LAST WATTAGE 1/16W
J 2
(-6375 2350);
DISPLAY 0.638298 (-6375 2350);
PAINT SKYBLUE (-6375 2350);
DISPLAY INVISIBLE (-6375 2350);
FORCEPROP 2 LAST CDS_LIB pure_quanta
J 0
(-6600 2225);
DISPLAY INVISIBLE (-6600 2225);
FORCEPROP 1 LAST PATH I322
J 0
(-6650 2375);
DISPLAY 0.978723 (-6650 2375);
PAINT WHITE (-6650 2375);
DISPLAY INVISIBLE (-6650 2375);
FORCEPROP 1 LAST PART_NUMBER CS01502FB03
J 0
(-6450 2200);
DISPLAY 0.489362 (-6450 2200);
PAINT SKYBLUE (-6450 2200);
DISPLAY INVISIBLE (-6450 2200);
FORCEADD OFFPAGE..5
(-6525 2125);
FORCEPROP 2 LAST $XR0 98 
J 0
(-6749 2125);
DISPLAY 0.638298 (-6749 2125);
PAINT MONO (-6749 2125);
FORCEPROP 2 LAST CDS_LIB standard
J 0
(-6525 2125);
DISPLAY INVISIBLE (-6525 2125);
FORCEPROP 1 LAST OFFPAGE TRUE
J 0
(-6200 2000);
DISPLAY 0.872340 (-6200 2000);
PAINT GREEN (-6200 2000);
DISPLAY INVISIBLE (-6200 2000);
FORCEPROP 1 LAST COMMENT_BODY TRUE
J 0
(-6425 2050);
DISPLAY 0.872340 (-6425 2050);
PAINT GREEN (-6425 2050);
DISPLAY INVISIBLE (-6425 2050);
FORCEPROP 2 LAST PATH I323
J 0
(-6775 2175);
DISPLAY 1.021277 (-6775 2175);
DISPLAY INVISIBLE (-6775 2175);
FORCEADD OFFPAGE..1
(-7475 2225);
FORCEPROP 2 LAST $XR0 98 
J 0
(-7726 2225);
DISPLAY 0.638298 (-7726 2225);
PAINT MONO (-7726 2225);
FORCEPROP 2 LAST CDS_LIB mstr_standard
J 0
(-7475 2225);
DISPLAY INVISIBLE (-7475 2225);
FORCEPROP 1 LAST OFFPAGE TRUE
J 0
(-7150 2100);
DISPLAY 0.872340 (-7150 2100);
PAINT GREEN (-7150 2100);
DISPLAY INVISIBLE (-7150 2100);
FORCEPROP 1 LAST COMMENT_BODY TRUE
J 0
(-7350 2125);
DISPLAY 0.872340 (-7350 2125);
PAINT GREEN (-7350 2125);
DISPLAY INVISIBLE (-7350 2125);
FORCEPROP 2 LAST PATH I324
J 0
(-7725 2275);
DISPLAY 1.021277 (-7725 2275);
DISPLAY INVISIBLE (-7725 2275);
FORCEADD CAD_NOTE..1
(-7675 2525);
FORCEPROP 0 LAST L1 R1958 PLACE CLOSE TO CPU < 25MM
J 0
(-7825 2400);
DISPLAY 0.617021 (-7825 2400);
PAINT WHITE (-7825 2400);
FORCEPROP 2 LAST CDS_LIB pure_quanta_power
J 0
(-7675 2525);
DISPLAY INVISIBLE (-7675 2525);
FORCEPROP 1 LAST COMMENT_BODY TRUE
J 0
(-7650 2625);
DISPLAY 0.574468 (-7650 2625);
PAINT WHITE (-7650 2625);
DISPLAY INVISIBLE (-7650 2625);
FORCEADD QUANTA_TITLE_BLOCK_C..1
(-100 100);
FORCEPROP 0 LAST CDS_CON_LAST_MODIFIED Thu Sep 14 16:11:55 2023
J 0
(-1985 115);
DISPLAY INVISIBLE (-1985 115);
FORCEPROP 1 LAST CUSTOM_TXT_CDS <CON_LAST_MODIFIED>
J 0
(-1985 115);
DISPLAY 0.978723 (-1985 115);
FORCEPROP 2 LAST CUSTOM_TXT_CDS <XR_PAGE_TITLE>
J 0
(-7990 5350);
DISPLAY 0.638298 (-7990 5350);
PAINT PINK (-7990 5350);
DISPLAY INVISIBLE (-7990 5350);
FORCEPROP 1 LAST CUSTOM_TXT_CDS <NAME_2>
J 0
(-3275 150);
FORCEPROP 1 LAST CUSTOM_TXT_CDS <NAME_1>
J 0
(-3275 275);
FORCEPROP 1 LAST CUSTOM_TXT_CDS <Q_NUMBER>
J 0
(-1503 203);
DISPLAY 1.212766 (-1503 203);
FORCEPROP 1 LAST CUSTOM_TXT_CDS <Q_PROJ>
J 0
(-2482 202);
DISPLAY 1.212766 (-2482 202);
FORCEPROP 1 LAST CUSTOM_TXT_CDS <Q_REV>
J 0
(-284 203);
DISPLAY 1.212766 (-284 203);
FORCEPROP 1 LAST CUSTOM_TXT_CDS <CON_PAGE_NUM> OF <CON_TOTAL_PAGES>
J 0
(-546 118);
DISPLAY 0.978723 (-546 118);
FORCEPROP 1 LAST Q_TITLE CPU1 DDR CHA
J 0
(-9400 175);
DISPLAY 2.446809 (-9400 175);
PAINT GREEN (-9400 175);
FORCEPROP 2 LAST PAGE_BORDER TRUE
J 0
(-7990 5350);
DISPLAY 0.638298 (-7990 5350);
PAINT PINK (-7990 5350);
DISPLAY INVISIBLE (-7990 5350);
FORCEPROP 1 LAST CDS_LMAN_SYM_OUTLINE -9475,6775,100,-125
J 0
(-100 100);
DISPLAY 0.468085 (-100 100);
PAINT GREEN (-100 100);
DISPLAY INVISIBLE (-100 100);
FORCEPROP 2 LAST CDS_LIB pure_quanta
J 0
(-100 100);
DISPLAY INVISIBLE (-100 100);
FORCEPROP 2 LAST CDS_XR_PAGE_TITLE CR-37 : @T6G_MB_LIB.T6G(SCH_1):PAGE37
J 0
(-7990 5350);
DISPLAY 0.638298 (-7990 5350);
PAINT PINK (-7990 5350);
DISPLAY INVISIBLE (-7990 5350);
FORCEPROP 1 LAST Q_DEPT BU9
J 1
(-3863 149);
DISPLAY 1.957447 (-3863 149);
PAINT GREEN (-3863 149);
DISPLAY INVISIBLE (-3863 149);
FORCEPROP 1 LAST COMMENT_BODY TRUE
J 0
(-88 87);
DISPLAY 0.978723 (-88 87);
PAINT GREEN (-88 87);
DISPLAY INVISIBLE (-88 87);
WIRE 17 -1 (-3250 5950)(-3250 5900);
WIRE 17 -1 (-3250 6000)(-3250 5950);
WIRE 17 -1 (-3250 5900)(-3250 5850);
WIRE 17 -1 (-3250 5850)(-3250 5800);
WIRE 17 -1 (-3250 6050)(-3250 6000);
WIRE 17 -1 (-3250 6100)(-3250 6050);
WIRE 17 -1 (-3250 5800)(-3250 5750);
WIRE 17 -1 (-3250 5750)(-3250 5650);
WIRE 17 -1 (-3250 6100)(-2625 6100);
FORCEPROP 2 LAST SIG_NAME M_A_CPU1_SA_DQ<31:0>
J 2
(-2685 6110);
DISPLAY 0.489362 (-2685 6110);
WIRE 17 -1 (-3250 5650)(-3250 5600);
WIRE 17 -1 (-3250 5600)(-3250 5550);
WIRE 17 -1 (-3250 5550)(-3250 5500);
WIRE 17 -1 (-3250 5500)(-3250 5450);
WIRE 17 -1 (-3250 5450)(-3250 5400);
WIRE 17 -1 (-3250 5400)(-3250 5350);
WIRE 17 -1 (-3250 5350)(-3250 5300);
WIRE 17 -1 (-3250 5200)(-3250 5300);
WIRE 17 -1 (-3250 5150)(-3250 5200);
WIRE 17 -1 (-3250 5100)(-3250 5150);
WIRE 17 -1 (-3250 5050)(-3250 5100);
WIRE 17 -1 (-3250 5050)(-3250 5000);
WIRE 17 -1 (-3250 5000)(-3250 4950);
WIRE 17 -1 (-3250 4950)(-3250 4900);
WIRE 17 -1 (-3250 4900)(-3250 4850);
WIRE 17 -1 (-3250 4850)(-3250 4750);
WIRE 17 -1 (-3250 4750)(-3250 4700);
WIRE 17 -1 (-3250 4700)(-3250 4650);
WIRE 17 -1 (-3250 4650)(-3250 4600);
WIRE 17 -1 (-3250 4550)(-3250 4600);
WIRE 17 -1 (-3250 4500)(-3250 4550);
WIRE 17 -1 (-3250 4450)(-3250 4500);
WIRE 17 -1 (-3250 4400)(-3250 4450);
WIRE 17 -1 (-3250 4200)(-3250 4150);
WIRE 17 -1 (-3250 4250)(-3250 4200);
WIRE 17 -1 (-3250 4150)(-3250 4100);
WIRE 17 -1 (-3250 4100)(-3250 4050);
WIRE 17 -1 (-3250 4300)(-3250 4250);
WIRE 17 -1 (-3250 4300)(-2625 4300);
FORCEPROP 2 LAST SIG_NAME M_A_CPU1_SB_DQ<31:0>
J 2
(-2685 4310);
DISPLAY 0.489362 (-2685 4310);
WIRE 17 -1 (-3250 3300)(-3250 3350);
WIRE 17 -1 (-3250 3250)(-3250 3300);
WIRE 17 -1 (-3250 3350)(-3250 3400);
WIRE 17 -1 (-3250 3400)(-3250 3500);
WIRE 17 -1 (-3250 3250)(-3250 3200);
WIRE 17 -1 (-3250 3200)(-3250 3150);
WIRE 17 -1 (-3250 3550)(-3250 3500);
WIRE 17 -1 (-3250 3600)(-3250 3550);
WIRE 17 -1 (-3250 3150)(-3250 3100);
WIRE 17 -1 (-3250 3100)(-3250 3050);
WIRE 17 -1 (-3250 3650)(-3250 3600);
WIRE 17 -1 (-3250 3700)(-3250 3650);
WIRE 17 -1 (-3250 3050)(-3250 2950);
WIRE 17 -1 (-3250 2950)(-3250 2900);
WIRE 17 -1 (-3250 3750)(-3250 3700);
WIRE 17 -1 (-3250 3800)(-3250 3750);
WIRE 17 -1 (-3250 2900)(-3250 2850);
WIRE 17 -1 (-3250 2850)(-3250 2800);
WIRE 17 -1 (-3250 3850)(-3250 3800);
WIRE 17 -1 (-3250 3950)(-3250 3850);
WIRE 17 -1 (-3250 2750)(-3250 2800);
WIRE 17 -1 (-3250 2700)(-3250 2750);
WIRE 17 -1 (-3250 4000)(-3250 3950);
WIRE 17 -1 (-3250 4050)(-3250 4000);
WIRE 17 -1 (-3250 2650)(-3250 2700);
WIRE 17 -1 (-3250 2600)(-3250 2650);
WIRE 17 -1 (-3250 2500)(-3250 2525);
WIRE 17 -1 (-3250 2500)(-3250 2450);
WIRE 17 -1 (-3250 2525)(-2750 2525);
FORCEPROP 2 LAST SIG_NAME M_A_CPU1_SA_CB<7:0>
J 2
(-2750 2535);
DISPLAY 0.489362 (-2750 2535);
WIRE 17 -1 (-3250 2400)(-3250 2450);
WIRE 17 -1 (-3250 2400)(-3250 2350);
WIRE 17 -1 (-3250 2300)(-3250 2350);
WIRE 17 -1 (-3250 2250)(-3250 2300);
WIRE 17 -1 (-3250 2200)(-3250 2250);
WIRE 17 -1 (-3250 2150)(-3250 2200);
WIRE 17 -1 (-3250 2050)(-3250 2075);
WIRE 17 -1 (-3250 2050)(-3250 2000);
WIRE 17 -1 (-3250 2075)(-2750 2075);
FORCEPROP 2 LAST SIG_NAME M_A_CPU1_SB_CB<7:0>
J 2
(-2750 2085);
DISPLAY 0.489362 (-2750 2085);
WIRE 17 -1 (-3250 1950)(-3250 2000);
WIRE 17 -1 (-3250 1950)(-3250 1900);
WIRE 17 -1 (-3250 1850)(-3250 1900);
WIRE 17 -1 (-3250 1800)(-3250 1850);
WIRE 17 -1 (-3250 1750)(-3250 1800);
WIRE 17 -1 (-3250 1700)(-3250 1750);
WIRE 17 -1 (-5775 5400)(-5775 5500);
WIRE 17 -1 (-5775 5400)(-5775 5300);
WIRE 17 -1 (-5775 5500)(-5775 5600);
WIRE 17 -1 (-5775 5600)(-5775 5700);
WIRE 17 -1 (-5775 5300)(-5775 5200);
WIRE 17 -1 (-5775 5800)(-5775 5700);
WIRE 17 -1 (-5775 5900)(-5775 5800);
WIRE 17 -1 (-5775 6000)(-5775 5900);
WIRE 17 -1 (-5775 6100)(-5775 6000);
WIRE 17 -1 (-5775 6100)(-6575 6100);
FORCEPROP 2 LAST SIG_NAME M_A_CPU1_SA_DQS_DP<9:0>
J 2
(-6010 6110);
DISPLAY 0.489362 (-6010 6110);
WIRE 17 -1 (-5975 6050)(-5975 5950);
FORCEPROP 2 LAST SIG_NAME M_A_CPU1_SA_DQS_DN<9:0>
J 2
(-6010 6060);
DISPLAY 0.489362 (-6010 6060);
WIRE 17 -1 (-5975 5950)(-5975 5850);
WIRE 17 -1 (-5975 5850)(-5975 5750);
WIRE 17 -1 (-5975 5750)(-5975 5650);
WIRE 17 -1 (-5975 5550)(-5975 5650);
WIRE 17 -1 (-5975 5450)(-5975 5550);
WIRE 17 -1 (-5975 5350)(-5975 5450);
WIRE 17 -1 (-5975 5350)(-5975 5250);
WIRE 17 -1 (-5975 5250)(-5975 5150);
WIRE 17 -1 (-5975 4500)(-5975 4600);
WIRE 17 -1 (-5975 4400)(-5975 4500);
WIRE 17 -1 (-5975 4700)(-5975 4600);
WIRE 17 -1 (-5975 4800)(-5975 4700);
WIRE 17 -1 (-5975 4300)(-5975 4400);
WIRE 17 -1 (-5975 4300)(-5975 4200);
WIRE 17 -1 (-5975 4900)(-5975 4800);
WIRE 17 -1 (-5975 5000)(-5975 4900);
FORCEPROP 2 LAST SIG_NAME M_A_CPU1_SB_DQS_DN<9:0>
J 2
(-6010 5010);
DISPLAY 0.489362 (-6010 5010);
WIRE 17 -1 (-5775 5050)(-5775 4950);
WIRE 17 -1 (-5775 5050)(-6575 5050);
FORCEPROP 2 LAST SIG_NAME M_A_CPU1_SB_DQS_DP<9:0>
J 2
(-6010 5060);
DISPLAY 0.489362 (-6010 5060);
WIRE 17 -1 (-5975 4200)(-5975 4100);
WIRE 17 -1 (-5775 4950)(-5775 4850);
WIRE 17 -1 (-5775 4850)(-5775 4750);
WIRE 17 -1 (-5775 4750)(-5775 4650);
WIRE 17 -1 (-5775 4550)(-5775 4650);
WIRE 17 -1 (-5775 4450)(-5775 4550);
WIRE 17 -1 (-5775 4350)(-5775 4450);
WIRE 17 -1 (-5775 4350)(-5775 4250);
WIRE 17 -1 (-5775 4250)(-5775 4150);
WIRE 17 -1 (-5975 3900)(-5975 3950);
WIRE 17 -1 (-5975 3850)(-5975 3900);
WIRE 17 -1 (-5975 3950)(-6475 3950);
FORCEPROP 2 LAST SIG_NAME M_A_CPU1_SA_CA<6:0>
J 0
(-6475 3960);
DISPLAY 0.489362 (-6475 3960);
WIRE 17 -1 (-5975 3500)(-5975 3550);
WIRE 17 -1 (-5975 3450)(-5975 3500);
WIRE 17 -1 (-5975 3550)(-6475 3550);
FORCEPROP 2 LAST SIG_NAME M_A_CPU1_SB_CA<6:0>
J 0
(-6475 3560);
DISPLAY 0.489362 (-6475 3560);
WIRE 17 -1 (-5975 3800)(-5975 3850);
WIRE 17 -1 (-5975 3400)(-5975 3450);
WIRE 17 -1 (-5975 3750)(-5975 3800);
WIRE 17 -1 (-5975 3700)(-5975 3750);
WIRE 17 -1 (-5975 3650)(-5975 3700);
WIRE 17 -1 (-5975 3350)(-5975 3400);
WIRE 17 -1 (-5975 3300)(-5975 3350);
WIRE 17 -1 (-5975 3250)(-5975 3300);
WIRE 17 -1 (-5975 6050)(-6575 6050);
WIRE 17 -1 (-5975 5000)(-6575 5000);
WIRE 16 -1 (-7425 2225)(-6700 2225);
FORCEPROP 2 LAST SIG_NAME M_A_CPU1_ALERT_N
J 0
(-7385 2235);
DISPLAY 0.489362 (-7385 2235);
WIRE 16 -1 (-6500 2225)(-5375 2225);
FORCEPROP 2 LAST SIG_NAME M_A_CPU1_ALERT_R_N
J 0
(-6210 2235);
DISPLAY 0.489362 (-6210 2235);
FORCEPROP 2 LASTPROP $XRERR UNIQUE?
J 0
(-6450 2235);
DISPLAY 0.638298 (-6450 2235);
PAINT MONO (-6450 2235);
DISPLAY INVISIBLE (-6450 2235);
WIRE 16 -1 (-6475 1225)(-5375 1225);
FORCEPROP 2 LAST SIG_NAME TP_M_A_CPU1_SA_TEST40
J 0
(-6460 1235);
DISPLAY 0.489362 (-6460 1235);
FORCEPROP 2 LASTPROP $XRERR UNIQUE?
J 0
(-6715 1225);
DISPLAY 0.638298 (-6715 1225);
PAINT MONO (-6715 1225);
DISPLAY INVISIBLE (-6715 1225);
WIRE 16 -1 (-6475 1275)(-5375 1275);
FORCEPROP 2 LAST SIG_NAME TP_M_A_CPU1_SA_TEST39A
J 0
(-6460 1285);
DISPLAY 0.489362 (-6460 1285);
FORCEPROP 2 LASTPROP $XRERR UNIQUE?
J 0
(-6715 1275);
DISPLAY 0.638298 (-6715 1275);
PAINT MONO (-6715 1275);
DISPLAY INVISIBLE (-6715 1275);
WIRE 16 -1 (-6475 3075)(-5375 3075);
FORCEPROP 2 LAST SIG_NAME M_A_CPU1_CLK_DP<0>
J 0
(-6475 3085);
DISPLAY 0.489362 (-6475 3085);
WIRE 16 -1 (-6475 3025)(-5375 3025);
FORCEPROP 2 LAST SIG_NAME M_A_CPU1_CLK_DN<0>
J 0
(-6475 3035);
DISPLAY 0.489362 (-6475 3035);
WIRE 16 -1 (-6475 2925)(-5375 2925);
FORCEPROP 2 LAST SIG_NAME M_A_CPU1_SA_CS_N<0>
J 0
(-6475 2935);
DISPLAY 0.489362 (-6475 2935);
WIRE 16 -1 (-6475 2875)(-5375 2875);
FORCEPROP 2 LAST SIG_NAME M_A_CPU1_SA_CS_N<1>
J 0
(-6475 2885);
DISPLAY 0.489362 (-6475 2885);
WIRE 16 -1 (-6475 2775)(-5375 2775);
FORCEPROP 2 LAST SIG_NAME M_A_CPU1_SA_RSP<0>
J 0
(-6475 2785);
DISPLAY 0.489362 (-6475 2785);
WIRE 16 -1 (-6475 2675)(-5375 2675);
FORCEPROP 2 LAST SIG_NAME M_A_CPU1_SA_PAR
J 0
(-6475 2685);
DISPLAY 0.489362 (-6475 2685);
WIRE 16 -1 (-6475 2575)(-5375 2575);
FORCEPROP 2 LAST SIG_NAME M_A_CPU1_SB_CS_N<0>
J 0
(-6475 2585);
DISPLAY 0.489362 (-6475 2585);
WIRE 16 -1 (-6475 2525)(-5375 2525);
FORCEPROP 2 LAST SIG_NAME M_A_CPU1_SB_CS_N<1>
J 0
(-6475 2535);
DISPLAY 0.489362 (-6475 2535);
WIRE 16 -1 (-6475 2425)(-5375 2425);
FORCEPROP 2 LAST SIG_NAME M_A_CPU1_SB_RSP<0>
J 0
(-6475 2435);
DISPLAY 0.489362 (-6475 2435);
WIRE 16 -1 (-6475 2325)(-5375 2325);
FORCEPROP 2 LAST SIG_NAME M_A_CPU1_SB_PAR
J 0
(-6475 2335);
DISPLAY 0.489362 (-6475 2335);
WIRE 16 -1 (-6475 2125)(-5375 2125);
FORCEPROP 2 LAST SIG_NAME M_A_CPU1_RESET_N
J 0
(-6475 2135);
DISPLAY 0.489362 (-6475 2135);
WIRE 16 -1 (-5875 3225)(-5375 3225);
WIRE 16 -1 (-5875 3625)(-5375 3625);
WIRE 16 -1 (-5875 3275)(-5375 3275);
WIRE 16 -1 (-5875 3675)(-5375 3675);
WIRE 16 -1 (-5875 3325)(-5375 3325);
WIRE 16 -1 (-5875 3725)(-5375 3725);
WIRE 16 -1 (-5875 3375)(-5375 3375);
WIRE 16 -1 (-5875 3775)(-5375 3775);
WIRE 16 -1 (-5875 3425)(-5375 3425);
WIRE 16 -1 (-5875 3825)(-5375 3825);
WIRE 16 -1 (-5875 3475)(-5375 3475);
WIRE 16 -1 (-5875 3875)(-5375 3875);
WIRE 16 -1 (-5875 3525)(-5375 3525);
WIRE 16 -1 (-5875 3925)(-5375 3925);
WIRE 16 -1 (-5875 4075)(-5375 4075);
WIRE 16 -1 (-5675 4125)(-5375 4125);
WIRE 16 -1 (-5675 5025)(-5375 5025);
WIRE 16 -1 (-5875 4575)(-5375 4575);
WIRE 16 -1 (-5875 4675)(-5375 4675);
WIRE 16 -1 (-5875 4775)(-5375 4775);
WIRE 16 -1 (-5875 4875)(-5375 4875);
WIRE 16 -1 (-5875 4975)(-5375 4975);
WIRE 16 -1 (-5675 4225)(-5375 4225);
WIRE 16 -1 (-5675 4325)(-5375 4325);
WIRE 16 -1 (-5675 4425)(-5375 4425);
WIRE 16 -1 (-5675 4525)(-5375 4525);
WIRE 16 -1 (-5675 4625)(-5375 4625);
WIRE 16 -1 (-5875 4175)(-5375 4175);
WIRE 16 -1 (-5675 4725)(-5375 4725);
WIRE 16 -1 (-5875 4275)(-5375 4275);
WIRE 16 -1 (-5675 4825)(-5375 4825);
WIRE 16 -1 (-5875 4375)(-5375 4375);
WIRE 16 -1 (-5675 4925)(-5375 4925);
WIRE 16 -1 (-5875 4475)(-5375 4475);
WIRE 16 -1 (-5675 5475)(-5375 5475);
WIRE 16 -1 (-5675 5575)(-5375 5575);
WIRE 16 -1 (-5875 5125)(-5375 5125);
WIRE 16 -1 (-5675 5675)(-5375 5675);
WIRE 16 -1 (-5875 5225)(-5375 5225);
WIRE 16 -1 (-5675 5775)(-5375 5775);
WIRE 16 -1 (-5875 5325)(-5375 5325);
WIRE 16 -1 (-5675 5875)(-5375 5875);
WIRE 16 -1 (-5875 5425)(-5375 5425);
WIRE 16 -1 (-5675 5975)(-5375 5975);
WIRE 16 -1 (-5875 5525)(-5375 5525);
WIRE 16 -1 (-5675 6075)(-5375 6075);
WIRE 16 -1 (-5875 5625)(-5375 5625);
WIRE 16 -1 (-5875 5725)(-5375 5725);
WIRE 16 -1 (-5875 5825)(-5375 5825);
WIRE 16 -1 (-5875 5925)(-5375 5925);
WIRE 16 -1 (-5875 6025)(-5375 6025);
WIRE 16 -1 (-5675 5175)(-5375 5175);
WIRE 16 -1 (-5675 5275)(-5375 5275);
WIRE 16 -1 (-5675 5375)(-5375 5375);
WIRE 16 -1 (-3775 1675)(-3350 1675);
WIRE 16 -1 (-3775 1725)(-3350 1725);
WIRE 16 -1 (-3775 1775)(-3350 1775);
WIRE 16 -1 (-3775 1825)(-3350 1825);
WIRE 16 -1 (-3775 1875)(-3350 1875);
WIRE 16 -1 (-3775 1925)(-3350 1925);
WIRE 16 -1 (-3775 1975)(-3350 1975);
WIRE 16 -1 (-3775 2025)(-3350 2025);
WIRE 16 -1 (-3775 2725)(-3350 2725);
WIRE 16 -1 (-3775 2775)(-3350 2775);
WIRE 16 -1 (-3775 2825)(-3350 2825);
WIRE 16 -1 (-3775 2875)(-3350 2875);
WIRE 16 -1 (-3775 2925)(-3350 2925);
WIRE 16 -1 (-3775 3025)(-3350 3025);
WIRE 16 -1 (-3775 2125)(-3350 2125);
WIRE 16 -1 (-3775 2175)(-3350 2175);
WIRE 16 -1 (-3775 2575)(-3350 2575);
WIRE 16 -1 (-3775 2225)(-3350 2225);
WIRE 16 -1 (-3775 2625)(-3350 2625);
WIRE 16 -1 (-3775 2275)(-3350 2275);
WIRE 16 -1 (-3775 2325)(-3350 2325);
WIRE 16 -1 (-3775 2375)(-3350 2375);
WIRE 16 -1 (-3775 2425)(-3350 2425);
WIRE 16 -1 (-3775 2475)(-3350 2475);
WIRE 16 -1 (-3775 2675)(-3350 2675);
WIRE 16 -1 (-3775 3325)(-3350 3325);
WIRE 16 -1 (-3775 3375)(-3350 3375);
WIRE 16 -1 (-3775 3475)(-3350 3475);
WIRE 16 -1 (-3775 3525)(-3350 3525);
WIRE 16 -1 (-3775 3575)(-3350 3575);
WIRE 16 -1 (-3775 3625)(-3350 3625);
WIRE 16 -1 (-3775 3675)(-3350 3675);
WIRE 16 -1 (-3775 3075)(-3350 3075);
WIRE 16 -1 (-3775 3725)(-3350 3725);
WIRE 16 -1 (-3775 3125)(-3350 3125);
WIRE 16 -1 (-3775 3175)(-3350 3175);
WIRE 16 -1 (-3775 3775)(-3350 3775);
WIRE 16 -1 (-3775 3825)(-3350 3825);
WIRE 16 -1 (-3775 3925)(-3350 3925);
WIRE 16 -1 (-3775 3975)(-3350 3975);
WIRE 16 -1 (-3775 4025)(-3350 4025);
WIRE 16 -1 (-3775 4075)(-3350 4075);
WIRE 16 -1 (-3775 3225)(-3350 3225);
WIRE 16 -1 (-3775 3275)(-3350 3275);
WIRE 16 -1 (-3775 4175)(-3350 4175);
WIRE 16 -1 (-3775 4225)(-3350 4225);
WIRE 16 -1 (-3775 4275)(-3350 4275);
WIRE 16 -1 (-3775 5025)(-3350 5025);
WIRE 16 -1 (-3775 5075)(-3350 5075);
WIRE 16 -1 (-3775 4475)(-3350 4475);
WIRE 16 -1 (-3775 4525)(-3350 4525);
WIRE 16 -1 (-3775 4575)(-3350 4575);
WIRE 16 -1 (-3775 4625)(-3350 4625);
WIRE 16 -1 (-3775 4675)(-3350 4675);
WIRE 16 -1 (-3775 4725)(-3350 4725);
WIRE 16 -1 (-3775 4825)(-3350 4825);
WIRE 16 -1 (-3775 4875)(-3350 4875);
WIRE 16 -1 (-3775 4925)(-3350 4925);
WIRE 16 -1 (-3775 4975)(-3350 4975);
WIRE 16 -1 (-3775 4375)(-3350 4375);
WIRE 16 -1 (-3775 4425)(-3350 4425);
WIRE 16 -1 (-3775 4125)(-3350 4125);
WIRE 16 -1 (-3775 5925)(-3350 5925);
WIRE 16 -1 (-3775 5975)(-3350 5975);
WIRE 16 -1 (-3775 6025)(-3350 6025);
WIRE 16 -1 (-3775 6075)(-3350 6075);
WIRE 16 -1 (-3775 5125)(-3350 5125);
WIRE 16 -1 (-3775 5175)(-3350 5175);
WIRE 16 -1 (-3775 5275)(-3350 5275);
WIRE 16 -1 (-3775 5325)(-3350 5325);
WIRE 16 -1 (-3775 5375)(-3350 5375);
WIRE 16 -1 (-3775 5575)(-3350 5575);
WIRE 16 -1 (-3775 5425)(-3350 5425);
WIRE 16 -1 (-3775 5625)(-3350 5625);
WIRE 16 -1 (-3775 5475)(-3350 5475);
WIRE 16 -1 (-3775 5725)(-3350 5725);
WIRE 16 -1 (-3775 5525)(-3350 5525);
WIRE 16 -1 (-3775 5775)(-3350 5775);
WIRE 16 -1 (-3775 5825)(-3350 5825);
WIRE 16 -1 (-3775 5875)(-3350 5875);
QUIT
